FILE_TYPE = MACRO_DRAWING;
SET COLOR_WIRE YELLOW;
SET COLOR_PROP ORANGE;
SET COLOR_DOT WHITE;
SET COLOR_ARC YELLOW;
SET COLOR_BODY GREEN;
SET COLOR_NOTE PURPLE;
SET PROP_DISPLAY VALUE;
SET PAGE_NUMBER P323;
FORCEADD OFFPAGE..1
(-175 -1350);
PAINT AQUA (-175 -1350);
FORCEPROP 2 LAST $XR0 81 
J 0
(-396 -1350);
DISPLAY 0.638298 (-396 -1350);
PAINT MONO (-396 -1350);
FORCEPROP 2 LAST $XR1 83 
J 0
(-486 -1350);
DISPLAY 0.638298 (-486 -1350);
PAINT MONO (-486 -1350);
FORCEPROP 2 LAST $XR2 146 
J 0
(-606 -1350);
DISPLAY 0.638298 (-606 -1350);
PAINT MONO (-606 -1350);
FORCEPROP 2 LAST CDS_LIB standard
J 0
(-175 -1350);
DISPLAY INVISIBLE (-175 -1350);
FORCEPROP 1 LAST OFFPAGE TRUE
J 0
(150 -1475);
DISPLAY 0.872340 (150 -1475);
PAINT AQUA (150 -1475);
DISPLAY INVISIBLE (150 -1475);
FORCEPROP 1 LAST COMMENT_BODY TRUE
J 0
(-50 -1450);
DISPLAY 0.872340 (-50 -1450);
PAINT GREEN (-50 -1450);
DISPLAY INVISIBLE (-50 -1450);
FORCEPROP 2 LAST PATH I1
J 0
(-450 -1300);
DISPLAY 1.021277 (-450 -1300);
DISPLAY INVISIBLE (-450 -1300);
FORCEADD UNIVERSAL_POWER..1
R 2
(975 -750);
FORCEPROP 3 LASTPIN (975 -800) SIG_NAME P3V3_AUX\g
J 0
(985 -790);
DISPLAY 0.659574 (985 -790);
PAINT MONO (985 -790);
DISPLAY INVISIBLE (985 -790);
FORCEPROP 1 LAST HDL_POWER P3V3_AUX
J 1
(975 -700);
DISPLAY 0.723404 (975 -700);
PAINT GREEN (975 -700);
FORCEPROP 2 LAST CDS_LIB pure_quanta_power
J 0
(975 -750);
DISPLAY INVISIBLE (975 -750);
FORCEPROP 1 LAST PATH I10
J 2
(925 -725);
DISPLAY 0.872340 (925 -725);
PAINT AQUA (925 -725);
DISPLAY INVISIBLE (925 -725);
FORCEADD OFFPAGE..1
(-2100 1425);
PAINT AQUA (-2100 1425);
FORCEPROP 2 LAST $XR0 81 
J 0
(-2321 1425);
DISPLAY 0.638298 (-2321 1425);
PAINT MONO (-2321 1425);
FORCEPROP 2 LAST $XR1 83 
J 0
(-2411 1425);
DISPLAY 0.638298 (-2411 1425);
PAINT MONO (-2411 1425);
FORCEPROP 2 LAST $XR2 146 
J 0
(-2531 1425);
DISPLAY 0.638298 (-2531 1425);
PAINT MONO (-2531 1425);
FORCEPROP 2 LAST CDS_LIB standard
J 0
(-2100 1425);
DISPLAY INVISIBLE (-2100 1425);
FORCEPROP 1 LAST OFFPAGE TRUE
J 0
(-1775 1300);
DISPLAY 0.872340 (-1775 1300);
PAINT AQUA (-1775 1300);
DISPLAY INVISIBLE (-1775 1300);
FORCEPROP 1 LAST COMMENT_BODY TRUE
J 0
(-1975 1325);
DISPLAY 0.872340 (-1975 1325);
PAINT GREEN (-1975 1325);
DISPLAY INVISIBLE (-1975 1325);
FORCEPROP 2 LAST PATH I11
J 0
(-2350 1475);
DISPLAY 1.021277 (-2350 1475);
DISPLAY INVISIBLE (-2350 1475);
FORCEADD GND..1
(-2050 625);
FORCEPROP 3 LASTPIN (-2050 675) SIG_NAME GND\g
J 0
(-2040 685);
DISPLAY 0.659574 (-2040 685);
PAINT MONO (-2040 685);
DISPLAY INVISIBLE (-2040 685);
FORCEPROP 2 LAST CDS_LIB pure_quanta_power
J 0
(-2050 625);
DISPLAY INVISIBLE (-2050 625);
FORCEPROP 1 LAST SIZE 1B
J 0
(-1975 575);
DISPLAY 0.872340 (-1975 575);
PAINT GREEN (-1975 575);
DISPLAY INVISIBLE (-1975 575);
FORCEPROP 1 LAST HDL_POWER GND
J 0
(-2050 775);
DISPLAY 0.872340 (-2050 775);
PAINT GREEN (-2050 775);
DISPLAY INVISIBLE (-2050 775);
FORCEPROP 1 LAST PATH I12
J 0
(-1975 625);
DISPLAY 0.872340 (-1975 625);
PAINT AQUA (-1975 625);
DISPLAY INVISIBLE (-1975 625);
FORCEADD Q_CAP..1
(-2050 975);
FORCEPROP 1 LAST LOCATION PC2196
J 0
(-2000 1025);
DISPLAY 0.638298 (-2000 1025);
FORCEPROP 0 LAST $SEC 1
J 0
(-2000 1125);
DISPLAY INVISIBLE (-2000 1125);
FORCEPROP 0 LAST CDS_SEC 1
J 0
(-2000 1125);
DISPLAY INVISIBLE (-2000 1125);
FORCEPROP 1 LASTPIN (-2050 1075) $PN 1
J 0
(-2040 1055);
DISPLAY 0.787234 (-2040 1055);
PAINT MONO (-2040 1055);
DISPLAY INVISIBLE (-2040 1055);
FORCEPROP 1 LASTPIN (-2050 875) $PN 2
J 0
(-2040 855);
DISPLAY 0.787234 (-2040 855);
PAINT MONO (-2040 855);
DISPLAY INVISIBLE (-2040 855);
FORCEPROP 0 LAST ROOM E1S_P12V_MPS_MAM_BOM2
J 0
(-2125 850);
DISPLAY 0.446809 (-2125 850);
PAINT RED (-2125 850);
FORCEPROP 1 LAST MATERIAL X7R
J 0
(-2000 950);
DISPLAY 0.510638 (-2000 950);
PAINT RED (-2000 950);
FORCEPROP 1 LAST PACK_TYPE 0402
J 0
(-2000 900);
DISPLAY 0.510638 (-2000 900);
FORCEPROP 1 LAST VOLTAGE 16V
J 0
(-2000 975);
DISPLAY 0.510638 (-2000 975);
FORCEPROP 1 LAST VALUE 0.22UF
J 0
(-2000 1000);
DISPLAY 0.510638 (-2000 1000);
FORCEPROP 2 LAST CDS_LIB pure_quanta
J 0
(-2050 975);
DISPLAY INVISIBLE (-2050 975);
FORCEPROP 1 LAST TOLERANCE 10%
J 0
(-2000 925);
DISPLAY 0.638298 (-2000 925);
DISPLAY INVISIBLE (-2000 925);
FORCEPROP 1 LAST PART_NUMBER CH4223K1B00
J 0
(-2000 925);
DISPLAY 0.510638 (-2000 925);
DISPLAY INVISIBLE (-2000 925);
FORCEPROP 1 LAST PATH I13
J 0
(-2000 1125);
DISPLAY 0.978723 (-2000 1125);
PAINT WHITE (-2000 1125);
DISPLAY INVISIBLE (-2000 1125);
FORCEADD GND..1
(-1625 550);
FORCEPROP 3 LASTPIN (-1625 600) SIG_NAME GND\g
J 0
(-1615 610);
DISPLAY 0.659574 (-1615 610);
PAINT MONO (-1615 610);
DISPLAY INVISIBLE (-1615 610);
FORCEPROP 2 LAST CDS_LIB pure_quanta_power
J 0
(-1625 550);
DISPLAY INVISIBLE (-1625 550);
FORCEPROP 1 LAST SIZE 1B
J 0
(-1550 500);
DISPLAY 0.872340 (-1550 500);
PAINT GREEN (-1550 500);
DISPLAY INVISIBLE (-1550 500);
FORCEPROP 1 LAST HDL_POWER GND
J 0
(-1625 700);
DISPLAY 0.872340 (-1625 700);
PAINT GREEN (-1625 700);
DISPLAY INVISIBLE (-1625 700);
FORCEPROP 1 LAST PATH I14
J 0
(-1550 550);
DISPLAY 0.872340 (-1550 550);
PAINT AQUA (-1550 550);
DISPLAY INVISIBLE (-1550 550);
FORCEADD Q_RES..2
(-1625 850);
FORCEPROP 1 LAST LOCATION PR3944
J 0
(-1575 900);
DISPLAY 0.638298 (-1575 900);
FORCEPROP 0 LAST $SEC 1
J 0
(-1575 1000);
DISPLAY 0.680851 (-1575 1000);
PAINT MONO (-1575 1000);
DISPLAY INVISIBLE (-1575 1000);
FORCEPROP 0 LAST CDS_SEC 1
J 0
(-1575 975);
DISPLAY INVISIBLE (-1575 975);
FORCEPROP 1 LASTPIN (-1625 950) $PN 1
J 0
(-1620 912);
DISPLAY 0.787234 (-1620 912);
PAINT MONO (-1620 912);
FORCEPROP 1 LASTPIN (-1625 750) $PN 2
J 0
(-1620 760);
DISPLAY 0.787234 (-1620 760);
PAINT MONO (-1620 760);
FORCEPROP 1 LAST PACK_TYPE 0402LF
J 0
(-1575 750);
DISPLAY 0.510638 (-1575 750);
FORCEPROP 0 LAST ROOM E1S_P12V_MPS_MAM_BOM2
J 0
(-1750 700);
DISPLAY 0.446809 (-1750 700);
PAINT RED (-1750 700);
FORCEPROP 1 LAST VALUE 46.4K
J 0
(-1575 875);
DISPLAY 0.510638 (-1575 875);
FORCEPROP 1 LAST WATTAGE 1/16W
J 0
(-1575 825);
DISPLAY 0.510638 (-1575 825);
FORCEPROP 1 LAST TOLERANCE 1%
J 0
(-1575 850);
DISPLAY 0.510638 (-1575 850);
FORCEPROP 1 LAST MATERIAL CHIP
J 0
(-1575 800);
DISPLAY 0.510638 (-1575 800);
PAINT RED (-1575 800);
FORCEPROP 2 LAST CDS_LIB pure_quanta
J 0
(-1625 850);
DISPLAY INVISIBLE (-1625 850);
FORCEPROP 1 LAST PART_NUMBER CS34642FB02
J 0
(-1575 775);
DISPLAY 0.510638 (-1575 775);
DISPLAY INVISIBLE (-1575 775);
FORCEPROP 1 LAST PATH I15
J 0
(-1575 1025);
DISPLAY 0.978723 (-1575 1025);
PAINT WHITE (-1575 1025);
DISPLAY INVISIBLE (-1575 1025);
FORCEADD GND..1
(-1275 350);
FORCEPROP 3 LASTPIN (-1275 400) SIG_NAME GND\g
J 0
(-1265 410);
DISPLAY 0.659574 (-1265 410);
PAINT MONO (-1265 410);
DISPLAY INVISIBLE (-1265 410);
FORCEPROP 1 LAST SIZE 1B
J 0
(-1200 300);
DISPLAY 0.872340 (-1200 300);
PAINT GREEN (-1200 300);
DISPLAY INVISIBLE (-1200 300);
FORCEPROP 2 LAST CDS_LIB pure_quanta_power
J 0
(-1275 350);
DISPLAY INVISIBLE (-1275 350);
FORCEPROP 1 LAST HDL_POWER GND
J 0
(-1275 500);
DISPLAY 0.872340 (-1275 500);
PAINT GREEN (-1275 500);
DISPLAY INVISIBLE (-1275 500);
FORCEPROP 1 LAST PATH I16
J 0
(-1200 350);
DISPLAY 0.872340 (-1200 350);
PAINT AQUA (-1200 350);
DISPLAY INVISIBLE (-1200 350);
FORCEADD Q_CAP..1
(-1275 575);
FORCEPROP 1 LAST LOCATION PC2341
J 0
(-1225 625);
DISPLAY 0.638298 (-1225 625);
FORCEPROP 0 LAST $SEC 1
J 0
(-1225 675);
DISPLAY 0.680851 (-1225 675);
PAINT MONO (-1225 675);
DISPLAY INVISIBLE (-1225 675);
FORCEPROP 0 LAST CDS_SEC 1
J 0
(-1225 675);
DISPLAY 1.021277 (-1225 675);
DISPLAY INVISIBLE (-1225 675);
FORCEPROP 1 LASTPIN (-1275 675) $PN 1
J 0
(-1265 655);
DISPLAY 0.787234 (-1265 655);
PAINT MONO (-1265 655);
FORCEPROP 1 LASTPIN (-1275 475) $PN 2
J 0
(-1265 455);
DISPLAY 0.787234 (-1265 455);
PAINT MONO (-1265 455);
FORCEPROP 1 LAST PACK_TYPE C0402
J 0
(-1225 500);
DISPLAY 0.510638 (-1225 500);
FORCEPROP 1 LAST VOLTAGE 50V
J 0
(-1225 575);
DISPLAY 0.510638 (-1225 575);
FORCEPROP 1 LAST MATERIAL X7R
J 0
(-1225 550);
DISPLAY 0.510638 (-1225 550);
PAINT RED (-1225 550);
FORCEPROP 1 LAST VALUE 560PF
J 0
(-1225 600);
DISPLAY 0.510638 (-1225 600);
FORCEPROP 0 LAST ROOM E1S_P12V_MPS_MAM_BOM2
J 0
(-1225 475);
DISPLAY 0.361702 (-1225 475);
PAINT RED (-1225 475);
FORCEPROP 2 LAST CDS_LIB pure_quanta
J 0
(-1275 575);
DISPLAY INVISIBLE (-1275 575);
FORCEPROP 1 LAST TOLERANCE 10%
J 0
(-1225 525);
DISPLAY 0.638298 (-1225 525);
DISPLAY INVISIBLE (-1225 525);
FORCEPROP 1 LAST PART_NUMBER CH1566K1B09
J 0
(-1225 525);
DISPLAY 0.510638 (-1225 525);
DISPLAY INVISIBLE (-1225 525);
FORCEPROP 1 LAST PATH I17
J 0
(-1225 725);
DISPLAY 0.978723 (-1225 725);
PAINT WHITE (-1225 725);
DISPLAY INVISIBLE (-1225 725);
FORCEADD Q_RES..2
(-1275 850);
FORCEPROP 1 LAST LOCATION PR4541
J 0
(-1225 900);
DISPLAY 0.638298 (-1225 900);
FORCEPROP 0 LAST $SEC 1
J 0
(-1225 950);
DISPLAY 0.680851 (-1225 950);
PAINT MONO (-1225 950);
DISPLAY INVISIBLE (-1225 950);
FORCEPROP 0 LAST CDS_SEC 1
J 0
(-1225 950);
DISPLAY 1.021277 (-1225 950);
DISPLAY INVISIBLE (-1225 950);
FORCEPROP 1 LASTPIN (-1275 950) $PN 1
J 0
(-1270 912);
DISPLAY 0.787234 (-1270 912);
PAINT MONO (-1270 912);
FORCEPROP 1 LASTPIN (-1275 750) $PN 2
J 0
(-1270 760);
DISPLAY 0.787234 (-1270 760);
PAINT MONO (-1270 760);
FORCEPROP 1 LAST PACK_TYPE 0402LF
J 0
(-1225 750);
DISPLAY 0.510638 (-1225 750);
FORCEPROP 0 LAST ROOM E1S_P12V_MPS_MAM_BOM2
J 0
(-1225 950);
DISPLAY 0.361702 (-1225 950);
PAINT RED (-1225 950);
FORCEPROP 1 LAST WATTAGE 1/16W
J 0
(-1225 825);
DISPLAY 0.510638 (-1225 825);
FORCEPROP 1 LAST VALUE 20K
J 0
(-1225 875);
DISPLAY 0.510638 (-1225 875);
FORCEPROP 1 LAST MATERIAL CHIP
J 0
(-1225 800);
DISPLAY 0.510638 (-1225 800);
PAINT RED (-1225 800);
FORCEPROP 1 LAST TOLERANCE 1%
J 0
(-1225 850);
DISPLAY 0.510638 (-1225 850);
FORCEPROP 2 LAST CDS_LIB pure_quanta
J 0
(-1275 850);
DISPLAY INVISIBLE (-1275 850);
FORCEPROP 1 LAST PART_NUMBER CS32002FB06
J 0
(-1225 775);
DISPLAY 0.510638 (-1225 775);
DISPLAY INVISIBLE (-1225 775);
FORCEPROP 1 LAST PATH I18
J 0
(-1225 1025);
DISPLAY 0.978723 (-1225 1025);
PAINT WHITE (-1225 1025);
DISPLAY INVISIBLE (-1225 1025);
FORCEADD Q_RES..1
(-1275 1425);
FORCEPROP 1 LAST LOCATION R3943
J 0
(-1325 1475);
DISPLAY 0.787234 (-1325 1475);
FORCEPROP 0 LAST $SEC 1
J 0
(-1325 1525);
DISPLAY 0.680851 (-1325 1525);
PAINT MONO (-1325 1525);
DISPLAY INVISIBLE (-1325 1525);
FORCEPROP 0 LAST CDS_SEC 1
J 0
(-1325 1525);
DISPLAY 1.021277 (-1325 1525);
DISPLAY INVISIBLE (-1325 1525);
FORCEPROP 1 LASTPIN (-1375 1425) $PN 1
J 0
(-1363 1437);
DISPLAY 0.787234 (-1363 1437);
PAINT MONO (-1363 1437);
FORCEPROP 1 LASTPIN (-1175 1425) $PN 2
J 0
(-1213 1437);
DISPLAY 0.787234 (-1213 1437);
PAINT MONO (-1213 1437);
FORCEPROP 1 LAST TOLERANCE 5%
J 0
(-1100 1425);
DISPLAY 0.510638 (-1100 1425);
FORCEPROP 1 LAST PACK_TYPE 0402LF
J 0
(-1025 1425);
DISPLAY 0.510638 (-1025 1425);
FORCEPROP 1 LAST MATERIAL CHIP
J 0
(-1350 1350);
DISPLAY 0.510638 (-1350 1350);
PAINT RED (-1350 1350);
FORCEPROP 1 LAST WATTAGE 1/16W
J 2
(-1075 1350);
DISPLAY 0.510638 (-1075 1350);
FORCEPROP 1 LAST VALUE 0
J 2
(-1125 1425);
DISPLAY 0.510638 (-1125 1425);
FORCEPROP 0 LAST ROOM E1S_P12V_MPS_MAM_BOM2
J 0
(-1475 1525);
DISPLAY 0.553191 (-1475 1525);
PAINT RED (-1475 1525);
FORCEPROP 2 LAST CDS_LIB pure_quanta
J 0
(-1275 1425);
DISPLAY INVISIBLE (-1275 1425);
FORCEPROP 1 LAST PART_NUMBER CS00002JB13
J 0
(-1350 1375);
DISPLAY 0.510638 (-1350 1375);
DISPLAY INVISIBLE (-1350 1375);
FORCEPROP 1 LAST PATH I19
J 0
(-1325 1575);
DISPLAY 0.978723 (-1325 1575);
PAINT WHITE (-1325 1575);
DISPLAY INVISIBLE (-1325 1575);
FORCEADD UNIVERSAL_GND..1
(325 -2025);
FORCEPROP 3 LASTPIN (325 -1975) SIG_NAME GND\g
J 0
(335 -1965);
DISPLAY 0.659574 (335 -1965);
PAINT MONO (335 -1965);
DISPLAY INVISIBLE (335 -1965);
FORCEPROP 2 LAST CDS_LIB pure_quanta_power
J 0
(325 -2025);
DISPLAY INVISIBLE (325 -2025);
FORCEPROP 1 LAST HDL_POWER GND
J 1
(350 -2100);
DISPLAY 0.872340 (350 -2100);
PAINT GREEN (350 -2100);
DISPLAY INVISIBLE (350 -2100);
FORCEPROP 1 LAST PATH I2
J 0
(400 -2025);
DISPLAY 0.872340 (400 -2025);
PAINT AQUA (400 -2025);
DISPLAY INVISIBLE (400 -2025);
FORCEADD GND..1
(-1150 1175);
FORCEPROP 3 LASTPIN (-1150 1225) SIG_NAME GND\g
J 0
(-1140 1235);
DISPLAY 0.659574 (-1140 1235);
PAINT MONO (-1140 1235);
DISPLAY INVISIBLE (-1140 1235);
FORCEPROP 1 LAST SIZE 1B
J 0
(-1075 1125);
DISPLAY 0.872340 (-1075 1125);
PAINT GREEN (-1075 1125);
DISPLAY INVISIBLE (-1075 1125);
FORCEPROP 2 LAST CDS_LIB pure_quanta_power
J 0
(-1150 1175);
DISPLAY INVISIBLE (-1150 1175);
FORCEPROP 1 LAST HDL_POWER GND
J 0
(-1150 1325);
DISPLAY 0.872340 (-1150 1325);
PAINT GREEN (-1150 1325);
DISPLAY INVISIBLE (-1150 1325);
FORCEPROP 1 LAST PATH I20
J 0
(-1075 1175);
DISPLAY 0.872340 (-1075 1175);
PAINT AQUA (-1075 1175);
DISPLAY INVISIBLE (-1075 1175);
FORCEADD GND..1
(-750 525);
FORCEPROP 3 LASTPIN (-750 575) SIG_NAME GND\g
J 0
(-740 585);
DISPLAY 0.659574 (-740 585);
PAINT MONO (-740 585);
DISPLAY INVISIBLE (-740 585);
FORCEPROP 1 LAST SIZE 1B
J 0
(-675 475);
DISPLAY 0.872340 (-675 475);
PAINT GREEN (-675 475);
DISPLAY INVISIBLE (-675 475);
FORCEPROP 2 LAST CDS_LIB pure_quanta_power
J 0
(-750 525);
DISPLAY INVISIBLE (-750 525);
FORCEPROP 1 LAST HDL_POWER GND
J 0
(-750 675);
DISPLAY 0.872340 (-750 675);
PAINT GREEN (-750 675);
DISPLAY INVISIBLE (-750 675);
FORCEPROP 1 LAST PATH I21
J 0
(-675 525);
DISPLAY 0.872340 (-675 525);
PAINT AQUA (-675 525);
DISPLAY INVISIBLE (-675 525);
FORCEADD Q_CAP..1
(-750 750);
FORCEPROP 1 LAST LOCATION PC2281
J 0
(-700 800);
DISPLAY 0.638298 (-700 800);
FORCEPROP 0 LAST $SEC 1
J 0
(-700 900);
DISPLAY INVISIBLE (-700 900);
FORCEPROP 0 LAST CDS_SEC 1
J 0
(-700 900);
DISPLAY INVISIBLE (-700 900);
FORCEPROP 1 LASTPIN (-750 850) $PN 1
J 0
(-740 830);
DISPLAY 0.787234 (-740 830);
PAINT MONO (-740 830);
DISPLAY INVISIBLE (-740 830);
FORCEPROP 1 LASTPIN (-750 650) $PN 2
J 0
(-740 630);
DISPLAY 0.787234 (-740 630);
PAINT MONO (-740 630);
DISPLAY INVISIBLE (-740 630);
FORCEPROP 0 LAST ROOM E1S_P12V_MPS_MAM_BOM2
J 0
(-700 625);
DISPLAY 0.446809 (-700 625);
PAINT RED (-700 625);
FORCEPROP 1 LAST PACK_TYPE C0402
J 0
(-700 675);
DISPLAY 0.510638 (-700 675);
FORCEPROP 1 LAST VOLTAGE 25V
J 0
(-700 750);
DISPLAY 0.510638 (-700 750);
FORCEPROP 1 LAST MATERIAL X7R
J 0
(-700 725);
DISPLAY 0.510638 (-700 725);
PAINT RED (-700 725);
FORCEPROP 1 LAST VALUE 0.047UF
J 0
(-700 775);
DISPLAY 0.510638 (-700 775);
FORCEPROP 2 LAST CDS_LIB pure_quanta
J 0
(-750 750);
DISPLAY INVISIBLE (-750 750);
FORCEPROP 1 LAST TOLERANCE 10%
J 0
(-700 700);
DISPLAY 0.638298 (-700 700);
DISPLAY INVISIBLE (-700 700);
FORCEPROP 1 LAST PART_NUMBER CH3474K1B04
J 0
(-700 700);
DISPLAY 0.510638 (-700 700);
DISPLAY INVISIBLE (-700 700);
FORCEPROP 1 LAST PATH I22
J 0
(-700 900);
DISPLAY 0.978723 (-700 900);
PAINT WHITE (-700 900);
DISPLAY INVISIBLE (-700 900);
FORCEADD GND..1
(-409 691);
FORCEPROP 3 LASTPIN (-409 741) SIG_NAME GND\g
J 0
(-399 751);
DISPLAY 0.659574 (-399 751);
PAINT MONO (-399 751);
DISPLAY INVISIBLE (-399 751);
FORCEPROP 1 LAST SIZE 1B
J 0
(-334 641);
DISPLAY 0.872340 (-334 641);
PAINT GREEN (-334 641);
DISPLAY INVISIBLE (-334 641);
FORCEPROP 2 LAST CDS_LIB pure_quanta_power
J 0
(-409 691);
DISPLAY INVISIBLE (-409 691);
FORCEPROP 1 LAST HDL_POWER GND
J 0
(-409 841);
DISPLAY 0.872340 (-409 841);
PAINT GREEN (-409 841);
DISPLAY INVISIBLE (-409 841);
FORCEPROP 1 LAST PATH I23
J 0
(-334 691);
DISPLAY 0.872340 (-334 691);
PAINT AQUA (-334 691);
DISPLAY INVISIBLE (-334 691);
FORCEADD Q_CAP..1
(-825 1825);
FORCEPROP 1 LAST LOCATION PC2198
J 0
(-775 1875);
DISPLAY 0.638298 (-775 1875);
FORCEPROP 0 LAST $SEC 1
J 0
(-770 1967);
DISPLAY INVISIBLE (-770 1967);
FORCEPROP 0 LAST CDS_SEC 1
J 0
(-770 1967);
DISPLAY INVISIBLE (-770 1967);
FORCEPROP 1 LASTPIN (-825 1925) $PN 1
J 0
(-815 1905);
DISPLAY 0.787234 (-815 1905);
PAINT MONO (-815 1905);
DISPLAY INVISIBLE (-815 1905);
FORCEPROP 1 LASTPIN (-825 1725) $PN 2
J 0
(-815 1705);
DISPLAY 0.787234 (-815 1705);
PAINT MONO (-815 1705);
DISPLAY INVISIBLE (-815 1705);
FORCEPROP 1 LAST MATERIAL X6S
J 0
(-775 1800);
DISPLAY 0.510638 (-775 1800);
PAINT RED (-775 1800);
FORCEPROP 1 LAST PACK_TYPE C0402
J 0
(-775 1750);
DISPLAY 0.510638 (-775 1750);
FORCEPROP 1 LAST VALUE 1UF
J 0
(-775 1850);
DISPLAY 0.510638 (-775 1850);
FORCEPROP 1 LAST VOLTAGE 25V
J 0
(-775 1825);
DISPLAY 0.510638 (-775 1825);
FORCEPROP 0 LAST ROOM E1S_P12V_MPS_MAM_BOM2
J 0
(-900 1925);
DISPLAY 0.446809 (-900 1925);
PAINT RED (-900 1925);
FORCEPROP 2 LAST CDS_LIB pure_quanta
J 0
(-825 1825);
DISPLAY INVISIBLE (-825 1825);
FORCEPROP 1 LAST TOLERANCE 10%
J 0
(-775 1775);
DISPLAY 0.638298 (-775 1775);
DISPLAY INVISIBLE (-775 1775);
FORCEPROP 1 LAST PART_NUMBER CH5104KEB02
J 0
(-775 1775);
DISPLAY 0.510638 (-775 1775);
DISPLAY INVISIBLE (-775 1775);
FORCEPROP 1 LAST PATH I25
J 0
(-775 1975);
DISPLAY 0.978723 (-775 1975);
PAINT WHITE (-775 1975);
DISPLAY INVISIBLE (-775 1975);
FORCEADD GND..1
(-825 1600);
FORCEPROP 3 LASTPIN (-825 1650) SIG_NAME GND\g
J 0
(-815 1660);
DISPLAY 0.659574 (-815 1660);
PAINT MONO (-815 1660);
DISPLAY INVISIBLE (-815 1660);
FORCEPROP 2 LAST CDS_LIB pure_quanta_power
J 0
(-825 1600);
DISPLAY INVISIBLE (-825 1600);
FORCEPROP 1 LAST SIZE 1B
J 0
(-750 1550);
DISPLAY 0.872340 (-750 1550);
PAINT GREEN (-750 1550);
DISPLAY INVISIBLE (-750 1550);
FORCEPROP 1 LAST HDL_POWER GND
J 0
(-825 1750);
DISPLAY 0.872340 (-825 1750);
PAINT GREEN (-825 1750);
DISPLAY INVISIBLE (-825 1750);
FORCEPROP 1 LAST PATH I26
J 0
(-750 1600);
DISPLAY 0.872340 (-750 1600);
PAINT AQUA (-750 1600);
DISPLAY INVISIBLE (-750 1600);
FORCEADD UNIVERSAL_POWER..1
(-825 2175);
FORCEPROP 3 LASTPIN (-825 2125) SIG_NAME P12V_AUX\g
J 0
(-815 2135);
DISPLAY 0.659574 (-815 2135);
PAINT MONO (-815 2135);
DISPLAY INVISIBLE (-815 2135);
FORCEPROP 1 LAST HDL_POWER P12V_AUX
J 1
(-825 2225);
DISPLAY 0.872340 (-825 2225);
PAINT GREEN (-825 2225);
FORCEPROP 2 LAST CDS_LIB pure_quanta_power
J 0
(-825 2175);
DISPLAY INVISIBLE (-825 2175);
FORCEPROP 1 LAST PATH I27
J 0
(-775 2200);
DISPLAY 0.872340 (-775 2200);
PAINT AQUA (-775 2200);
DISPLAY INVISIBLE (-775 2200);
FORCEADD UNIVERSAL_GND..1
(3050 -2150);
FORCEPROP 3 LASTPIN (3050 -2100) SIG_NAME GND\g
J 0
(3060 -2090);
DISPLAY 0.659574 (3060 -2090);
PAINT MONO (3060 -2090);
DISPLAY INVISIBLE (3060 -2090);
FORCEPROP 2 LAST CDS_LIB pure_quanta_power
J 0
(3050 -2150);
DISPLAY INVISIBLE (3050 -2150);
FORCEPROP 1 LAST HDL_POWER GND
J 1
(3075 -2225);
DISPLAY 0.872340 (3075 -2225);
PAINT GREEN (3075 -2225);
DISPLAY INVISIBLE (3075 -2225);
FORCEPROP 1 LAST PATH I28
J 0
(3125 -2150);
DISPLAY 0.872340 (3125 -2150);
PAINT AQUA (3125 -2150);
DISPLAY INVISIBLE (3125 -2150);
FORCEADD UNIVERSAL_GND..1
(1550 -2025);
FORCEPROP 3 LASTPIN (1550 -1975) SIG_NAME GND\g
J 0
(1560 -1965);
DISPLAY 0.659574 (1560 -1965);
PAINT MONO (1560 -1965);
DISPLAY INVISIBLE (1560 -1965);
FORCEPROP 2 LAST CDS_LIB pure_quanta_power
J 0
(1550 -2025);
DISPLAY INVISIBLE (1550 -2025);
FORCEPROP 1 LAST HDL_POWER GND
J 1
(1575 -2100);
DISPLAY 0.872340 (1575 -2100);
PAINT GREEN (1575 -2100);
DISPLAY INVISIBLE (1575 -2100);
FORCEPROP 1 LAST PATH I29
J 0
(1625 -2025);
DISPLAY 0.872340 (1625 -2025);
PAINT AQUA (1625 -2025);
DISPLAY INVISIBLE (1625 -2025);
FORCEADD Q_CAP..1
(325 -1650);
FORCEPROP 1 LAST LOCATION PC2197
J 0
(400 -1625);
DISPLAY 0.574468 (400 -1625);
FORCEPROP 0 LAST $SEC 1
J 0
(375 -1525);
DISPLAY INVISIBLE (375 -1525);
FORCEPROP 0 LAST CDS_SEC 1
J 0
(375 -1525);
DISPLAY INVISIBLE (375 -1525);
FORCEPROP 1 LASTPIN (325 -1550) $PN 1
J 0
(335 -1570);
DISPLAY 0.787234 (335 -1570);
PAINT MONO (335 -1570);
DISPLAY INVISIBLE (335 -1570);
FORCEPROP 1 LASTPIN (325 -1750) $PN 2
J 0
(335 -1770);
DISPLAY 0.787234 (335 -1770);
PAINT MONO (335 -1770);
DISPLAY INVISIBLE (335 -1770);
FORCEPROP 1 LAST PACK_TYPE 0402
J 0
(400 -1750);
DISPLAY 0.468085 (400 -1750);
FORCEPROP 1 LAST MATERIAL NPO
J 0
(400 -1700);
DISPLAY 0.468085 (400 -1700);
PAINT RED (400 -1700);
FORCEPROP 1 LAST VOLTAGE 50V
J 0
(400 -1675);
DISPLAY 0.468085 (400 -1675);
FORCEPROP 0 LAST ROOM E1S_P3V3_BOM2
J 0
(375 -1800);
DISPLAY 0.446809 (375 -1800);
PAINT RED (375 -1800);
FORCEPROP 1 LAST VALUE 39PF
J 0
(400 -1650);
DISPLAY 0.468085 (400 -1650);
FORCEPROP 2 LAST CDS_LIB pure_quanta
J 0
(325 -1650);
DISPLAY INVISIBLE (325 -1650);
FORCEPROP 1 LAST TOLERANCE 5%
J 0
(375 -1700);
DISPLAY 0.723404 (375 -1700);
PAINT SKYBLUE (375 -1700);
DISPLAY INVISIBLE (375 -1700);
FORCEPROP 1 LAST PART_NUMBER CH03906JB06
J 0
(400 -1725);
DISPLAY 0.468085 (400 -1725);
DISPLAY INVISIBLE (400 -1725);
FORCEPROP 1 LAST PATH I3
J 0
(375 -1500);
DISPLAY 0.978723 (375 -1500);
PAINT WHITE (375 -1500);
DISPLAY INVISIBLE (375 -1500);
FORCEADD Q_CAP..1
(1550 -1725);
FORCEPROP 1 LAST LOCATION PC2201
J 0
(1625 -1675);
DISPLAY 0.574468 (1625 -1675);
FORCEPROP 0 LAST $SEC 1
J 0
(1600 -1575);
DISPLAY INVISIBLE (1600 -1575);
FORCEPROP 0 LAST CDS_SEC 1
J 0
(1600 -1575);
DISPLAY INVISIBLE (1600 -1575);
FORCEPROP 1 LASTPIN (1550 -1625) $PN 1
J 0
(1560 -1645);
DISPLAY 0.787234 (1560 -1645);
PAINT MONO (1560 -1645);
DISPLAY INVISIBLE (1560 -1645);
FORCEPROP 1 LASTPIN (1550 -1825) $PN 2
J 0
(1560 -1845);
DISPLAY 0.787234 (1560 -1845);
PAINT MONO (1560 -1845);
DISPLAY INVISIBLE (1560 -1845);
FORCEPROP 1 LAST VALUE 0.068UF
J 0
(1625 -1700);
DISPLAY 0.468085 (1625 -1700);
FORCEPROP 1 LAST VOLTAGE 16V
J 0
(1625 -1725);
DISPLAY 0.468085 (1625 -1725);
FORCEPROP 1 LAST MATERIAL X7R
J 0
(1625 -1750);
DISPLAY 0.468085 (1625 -1750);
PAINT RED (1625 -1750);
FORCEPROP 1 LAST PACK_TYPE 0402
J 0
(1625 -1800);
DISPLAY 0.468085 (1625 -1800);
FORCEPROP 0 LAST ROOM E1S_P3V3_BOM2
J 0
(1625 -1850);
DISPLAY 0.680851 (1625 -1850);
PAINT RED (1625 -1850);
FORCEPROP 2 LAST CDS_LIB pure_quanta
J 0
(1550 -1725);
DISPLAY INVISIBLE (1550 -1725);
FORCEPROP 1 LAST TOLERANCE 10%
J 0
(1600 -1775);
DISPLAY 0.723404 (1600 -1775);
PAINT SKYBLUE (1600 -1775);
DISPLAY INVISIBLE (1600 -1775);
FORCEPROP 1 LAST PART_NUMBER CH3683K1B09
J 0
(1625 -1775);
DISPLAY 0.468085 (1625 -1775);
DISPLAY INVISIBLE (1625 -1775);
FORCEPROP 1 LAST PATH I30
J 0
(1600 -1575);
DISPLAY 0.978723 (1600 -1575);
PAINT WHITE (1600 -1575);
DISPLAY INVISIBLE (1600 -1575);
FORCEADD MP5016GQHLZ..1
(2200 -1400);
FORCEPROP 1 LAST LOCATION PU293
J 0
(1950 -925);
DISPLAY 0.723404 (1950 -925);
PAINT GREEN (1950 -925);
FORCEPROP 0 LAST $SEC 1
J 0
(1975 -775);
DISPLAY INVISIBLE (1975 -775);
FORCEPROP 0 LAST CDS_SEC 1
J 0
(1975 -775);
DISPLAY INVISIBLE (1975 -775);
FORCEPROP 0 LASTPIN (1800 -1550) $PN 10
J 2
(1790 -1540);
DISPLAY 0.808511 (1790 -1540);
FORCEPROP 0 LASTPIN (1800 -1350) $PN 9
J 2
(1790 -1340);
DISPLAY 0.808511 (1790 -1340);
FORCEPROP 0 LASTPIN (2600 -1450) $PN 8
J 0
(2610 -1440);
DISPLAY 0.808511 (2610 -1440);
FORCEPROP 0 LASTPIN (2600 -1550) $PN 3
J 0
(2610 -1540);
DISPLAY 0.808511 (2610 -1540);
FORCEPROP 0 LASTPIN (1800 -1500) $PN 4
J 2
(1790 -1490);
DISPLAY 0.808511 (1790 -1490);
FORCEPROP 0 LASTPIN (1800 -1450) $PN 5
J 2
(1790 -1440);
DISPLAY 0.808511 (1790 -1440);
FORCEPROP 0 LASTPIN (2600 -1250) $PN 6_7
J 0
(2610 -1240);
DISPLAY 0.808511 (2610 -1240);
FORCEPROP 0 LASTPIN (1800 -1250) $PN 1_2
J 2
(1790 -1240);
DISPLAY 0.808511 (1790 -1240);
FORCEPROP 1 LAST MATERIAL IC
J 0
(1955 -1193);
DISPLAY 0.723404 (1955 -1193);
PAINT RED (1955 -1193);
FORCEPROP 2 LAST VALUE MP5016GQH-L-Z
J 0
(1950 -1025);
DISPLAY 0.680851 (1950 -1025);
FORCEPROP 2 LAST PART_TYPE SMLF
J 0
(1950 -975);
DISPLAY 0.680851 (1950 -975);
FORCEPROP 0 LAST ROOM E1S_P3V3_BOM2
J 0
(1950 -825);
DISPLAY 0.680851 (1950 -825);
PAINT RED (1950 -825);
FORCEPROP 2 LAST CDS_LIB pure_quanta
J 0
(2200 -1400);
DISPLAY INVISIBLE (2200 -1400);
FORCEPROP 1 LAST CDS_LMAN_SYM_OUTLINE -250,200,250,-200
J 0
(2200 -1400);
DISPLAY 0.468085 (2200 -1400);
PAINT GREEN (2200 -1400);
DISPLAY INVISIBLE (2200 -1400);
FORCEPROP 1 LAST NEEDS_NO_SIZE TRUE
J 0
(2200 -1400);
DISPLAY 0.723404 (2200 -1400);
PAINT GREEN (2200 -1400);
DISPLAY INVISIBLE (2200 -1400);
FORCEPROP 1 LAST PART_NUMBER AL005016007
J 0
(1955 -1066);
DISPLAY 0.723404 (1955 -1066);
PAINT GREEN (1955 -1066);
DISPLAY INVISIBLE (1955 -1066);
FORCEPROP 1 LAST PATH I31
J 0
(2200 -1400);
DISPLAY 0.723404 (2200 -1400);
PAINT GREEN (2200 -1400);
DISPLAY INVISIBLE (2200 -1400);
FORCEADD Q_CAP..1
(3050 -1800);
FORCEPROP 1 LAST LOCATION PC2203
J 0
(3125 -1725);
DISPLAY 0.638298 (3125 -1725);
FORCEPROP 0 LAST $SEC 1
J 0
(3100 -1650);
DISPLAY INVISIBLE (3100 -1650);
FORCEPROP 0 LAST CDS_SEC 1
J 0
(3100 -1650);
DISPLAY INVISIBLE (3100 -1650);
FORCEPROP 1 LASTPIN (3050 -1700) $PN 1
J 0
(3060 -1720);
DISPLAY 0.787234 (3060 -1720);
PAINT MONO (3060 -1720);
DISPLAY INVISIBLE (3060 -1720);
FORCEPROP 1 LASTPIN (3050 -1900) $PN 2
J 0
(3060 -1920);
DISPLAY 0.787234 (3060 -1920);
PAINT MONO (3060 -1920);
DISPLAY INVISIBLE (3060 -1920);
FORCEPROP 1 LAST TOLERANCE 5%
J 0
(3125 -1800);
DISPLAY 0.510638 (3125 -1800);
FORCEPROP 0 LAST ROOM E1S_P3V3_BOM2
J 0
(3125 -1625);
DISPLAY 0.680851 (3125 -1625);
PAINT RED (3125 -1625);
FORCEPROP 1 LAST VOLTAGE 50V
J 0
(3125 -1775);
DISPLAY 0.510638 (3125 -1775);
FORCEPROP 1 LAST MATERIAL X7R
J 0
(3125 -1825);
DISPLAY 0.510638 (3125 -1825);
PAINT RED (3125 -1825);
FORCEPROP 1 LAST PACK_TYPE 0402
J 0
(3125 -1875);
DISPLAY 0.510638 (3125 -1875);
FORCEPROP 1 LAST VALUE 100PF
J 0
(3125 -1750);
DISPLAY 0.510638 (3125 -1750);
FORCEPROP 2 LAST CDS_LIB pure_quanta
J 0
(3050 -1800);
DISPLAY INVISIBLE (3050 -1800);
FORCEPROP 1 LAST PART_NUMBER CH11006JB18
J 0
(3125 -1850);
DISPLAY 0.510638 (3125 -1850);
DISPLAY INVISIBLE (3125 -1850);
FORCEPROP 1 LAST PATH I32
J 0
(3100 -1650);
DISPLAY 0.978723 (3100 -1650);
PAINT WHITE (3100 -1650);
DISPLAY INVISIBLE (3100 -1650);
FORCEADD UNIVERSAL_GND..1
(3650 -1925);
FORCEPROP 3 LASTPIN (3650 -1875) SIG_NAME GND\g
J 0
(3660 -1865);
DISPLAY 0.659574 (3660 -1865);
PAINT MONO (3660 -1865);
DISPLAY INVISIBLE (3660 -1865);
FORCEPROP 2 LAST CDS_LIB pure_quanta_power
J 0
(3650 -1925);
DISPLAY INVISIBLE (3650 -1925);
FORCEPROP 1 LAST HDL_POWER GND
J 1
(3675 -2000);
DISPLAY 0.872340 (3675 -2000);
PAINT GREEN (3675 -2000);
DISPLAY INVISIBLE (3675 -2000);
FORCEPROP 1 LAST PATH I33
J 0
(3725 -1925);
DISPLAY 0.872340 (3725 -1925);
PAINT AQUA (3725 -1925);
DISPLAY INVISIBLE (3725 -1925);
FORCEADD Q_CAP..1
(3650 -1575);
FORCEPROP 1 LAST LOCATION PC2204
J 0
(3725 -1525);
DISPLAY 0.723404 (3725 -1525);
FORCEPROP 0 LAST $SEC 1
J 0
(3700 -1450);
DISPLAY INVISIBLE (3700 -1450);
FORCEPROP 0 LAST CDS_SEC 1
J 0
(3700 -1450);
DISPLAY INVISIBLE (3700 -1450);
FORCEPROP 1 LASTPIN (3650 -1475) $PN 1
J 0
(3660 -1495);
DISPLAY 0.787234 (3660 -1495);
PAINT MONO (3660 -1495);
DISPLAY INVISIBLE (3660 -1495);
FORCEPROP 1 LASTPIN (3650 -1675) $PN 2
J 0
(3660 -1695);
DISPLAY 0.787234 (3660 -1695);
PAINT MONO (3660 -1695);
DISPLAY INVISIBLE (3660 -1695);
FORCEPROP 1 LAST PACK_TYPE C0805
J 0
(3725 -1650);
DISPLAY 0.574468 (3725 -1650);
FORCEPROP 1 LAST VOLTAGE 16V
J 0
(3725 -1575);
DISPLAY 0.574468 (3725 -1575);
FORCEPROP 1 LAST VALUE 10UF
J 0
(3725 -1550);
DISPLAY 0.574468 (3725 -1550);
FORCEPROP 1 LAST MATERIAL X6S
J 0
(3725 -1600);
DISPLAY 0.574468 (3725 -1600);
PAINT RED (3725 -1600);
FORCEPROP 0 LAST ROOM E1S_P3V3_BOM2
J 0
(3725 -1425);
DISPLAY 0.680851 (3725 -1425);
PAINT RED (3725 -1425);
FORCEPROP 1 LAST TOLERANCE 10%
J 0
(3700 -1625);
DISPLAY 0.723404 (3700 -1625);
PAINT SKYBLUE (3700 -1625);
DISPLAY INVISIBLE (3700 -1625);
FORCEPROP 2 LAST CDS_LIB pure_quanta
J 0
(3650 -1575);
DISPLAY INVISIBLE (3650 -1575);
FORCEPROP 1 LAST PART_NUMBER CH6103KEA01
J 0
(3725 -1625);
DISPLAY 0.574468 (3725 -1625);
DISPLAY INVISIBLE (3725 -1625);
FORCEPROP 1 LAST PATH I34
J 0
(3700 -1425);
DISPLAY 0.978723 (3700 -1425);
PAINT WHITE (3700 -1425);
DISPLAY INVISIBLE (3700 -1425);
FORCEADD UNIVERSAL_POWER..1
R 2
(3650 -925);
FORCEPROP 3 LASTPIN (3650 -975) SIG_NAME P3V3_E1S_0_R\g
J 0
(3660 -965);
DISPLAY 0.659574 (3660 -965);
PAINT MONO (3660 -965);
DISPLAY INVISIBLE (3660 -965);
FORCEPROP 1 LAST HDL_POWER P3V3_E1S_0_R
J 1
(3650 -875);
DISPLAY 0.723404 (3650 -875);
PAINT GREEN (3650 -875);
FORCEPROP 2 LAST CDS_LIB pure_quanta_power
J 0
(3650 -925);
DISPLAY INVISIBLE (3650 -925);
FORCEPROP 1 LAST PATH I35
J 2
(3600 -900);
DISPLAY 0.872340 (3600 -900);
PAINT AQUA (3600 -900);
DISPLAY INVISIBLE (3600 -900);
FORCEADD Q_RES..2
(675 550);
FORCEPROP 1 LAST LOCATION PR3949
J 0
(725 600);
DISPLAY 0.638298 (725 600);
FORCEPROP 0 LAST $SEC 1
J 0
(725 725);
DISPLAY 0.680851 (725 725);
PAINT MONO (725 725);
DISPLAY INVISIBLE (725 725);
FORCEPROP 0 LAST CDS_SEC 1
J 0
(725 725);
DISPLAY 1.021277 (725 725);
DISPLAY INVISIBLE (725 725);
FORCEPROP 1 LASTPIN (675 650) $PN 1
J 0
(680 612);
DISPLAY 0.787234 (680 612);
PAINT MONO (680 612);
FORCEPROP 1 LASTPIN (675 450) $PN 2
J 0
(680 460);
DISPLAY 0.787234 (680 460);
PAINT MONO (680 460);
FORCEPROP 0 LAST ROOM E1S_P12V_MPS_MAM_BOM2
J 0
(725 425);
DISPLAY 0.446809 (725 425);
PAINT RED (725 425);
FORCEPROP 1 LAST MATERIAL CHIP
J 0
(725 500);
DISPLAY 0.510638 (725 500);
PAINT RED (725 500);
FORCEPROP 1 LAST VALUE 56K
J 0
(725 575);
DISPLAY 0.510638 (725 575);
FORCEPROP 1 LAST TOLERANCE 1%
J 0
(725 550);
DISPLAY 0.510638 (725 550);
FORCEPROP 1 LAST WATTAGE 1/16W
J 0
(725 525);
DISPLAY 0.510638 (725 525);
FORCEPROP 1 LAST PACK_TYPE 0402LF
J 0
(725 450);
DISPLAY 0.510638 (725 450);
FORCEPROP 2 LAST CDS_LIB pure_quanta
J 0
(675 550);
DISPLAY INVISIBLE (675 550);
FORCEPROP 1 LAST PART_NUMBER CS35602FB00
J 0
(725 475);
DISPLAY 0.510638 (725 475);
DISPLAY INVISIBLE (725 475);
FORCEPROP 1 LAST PATH I36
J 0
(725 725);
DISPLAY 0.978723 (725 725);
PAINT WHITE (725 725);
DISPLAY INVISIBLE (725 725);
FORCEADD Q_RES..2
(525 2000);
FORCEPROP 1 LAST LOCATION R3948
J 0
(600 2075);
DISPLAY 0.638298 (600 2075);
FORCEPROP 0 LAST $SEC 1
J 0
(580 2217);
DISPLAY 0.680851 (580 2217);
PAINT MONO (580 2217);
DISPLAY INVISIBLE (580 2217);
FORCEPROP 0 LAST CDS_SEC 1
J 0
(575 2175);
DISPLAY INVISIBLE (575 2175);
FORCEPROP 1 LASTPIN (525 2100) $PN 1
J 0
(530 2062);
DISPLAY 0.787234 (530 2062);
PAINT MONO (530 2062);
FORCEPROP 1 LASTPIN (525 1900) $PN 2
J 0
(530 1910);
DISPLAY 0.787234 (530 1910);
PAINT MONO (530 1910);
FORCEPROP 0 LAST ROOM E1S_P12V_MPS_MAM_BOM2
J 0
(600 2125);
DISPLAY 0.553191 (600 2125);
PAINT RED (600 2125);
FORCEPROP 1 LAST PACK_TYPE 0402LF
J 0
(600 1925);
DISPLAY 0.510638 (600 1925);
FORCEPROP 1 LAST TOLERANCE 1%
J 0
(600 2025);
DISPLAY 0.510638 (600 2025);
FORCEPROP 1 LAST VALUE 10K
J 0
(600 2050);
DISPLAY 0.510638 (600 2050);
FORCEPROP 1 LAST WATTAGE 1/16W
J 0
(600 2000);
DISPLAY 0.510638 (600 2000);
FORCEPROP 1 LAST MATERIAL CHIP
J 0
(600 1975);
DISPLAY 0.510638 (600 1975);
PAINT RED (600 1975);
FORCEPROP 2 LAST CDS_LIB pure_quanta
J 0
(525 2000);
DISPLAY INVISIBLE (525 2000);
FORCEPROP 1 LAST PART_NUMBER CS31002FB08
J 0
(600 1950);
DISPLAY 0.510638 (600 1950);
DISPLAY INVISIBLE (600 1950);
FORCEPROP 1 LAST PATH I37
J 0
(575 2175);
DISPLAY 0.978723 (575 2175);
PAINT WHITE (575 2175);
DISPLAY INVISIBLE (575 2175);
FORCEADD GND..1
(1125 150);
FORCEPROP 3 LASTPIN (1125 200) SIG_NAME GND\g
J 0
(1135 210);
DISPLAY 0.659574 (1135 210);
PAINT MONO (1135 210);
DISPLAY INVISIBLE (1135 210);
FORCEPROP 1 LAST SIZE 1B
J 0
(1200 100);
DISPLAY 0.872340 (1200 100);
PAINT GREEN (1200 100);
DISPLAY INVISIBLE (1200 100);
FORCEPROP 2 LAST CDS_LIB pure_quanta_power
J 0
(1125 150);
DISPLAY INVISIBLE (1125 150);
FORCEPROP 1 LAST HDL_POWER GND
J 0
(1125 300);
DISPLAY 0.872340 (1125 300);
PAINT GREEN (1125 300);
DISPLAY INVISIBLE (1125 300);
FORCEPROP 1 LAST PATH I38
J 0
(1200 150);
DISPLAY 0.872340 (1200 150);
PAINT AQUA (1200 150);
DISPLAY INVISIBLE (1200 150);
FORCEADD Q_CAP..1
(1125 550);
FORCEPROP 1 LAST LOCATION PC2202
J 0
(1200 600);
DISPLAY 0.638298 (1200 600);
FORCEPROP 0 LAST $SEC 1
J 0
(1175 700);
DISPLAY INVISIBLE (1175 700);
FORCEPROP 0 LAST CDS_SEC 1
J 0
(1175 700);
DISPLAY INVISIBLE (1175 700);
FORCEPROP 1 LASTPIN (1125 650) $PN 1
J 0
(1135 630);
DISPLAY 0.787234 (1135 630);
PAINT MONO (1135 630);
DISPLAY INVISIBLE (1135 630);
FORCEPROP 1 LASTPIN (1125 450) $PN 2
J 0
(1135 430);
DISPLAY 0.787234 (1135 430);
PAINT MONO (1135 430);
DISPLAY INVISIBLE (1135 430);
FORCEPROP 0 LAST ROOM E1S_P12V_MPS_MAM_BOM2
J 0
(1200 650);
DISPLAY 0.446809 (1200 650);
PAINT RED (1200 650);
FORCEPROP 1 LAST PACK_TYPE C0402
J 0
(1200 475);
DISPLAY 0.510638 (1200 475);
FORCEPROP 1 LAST MATERIAL X7R
J 0
(1200 525);
DISPLAY 0.510638 (1200 525);
PAINT RED (1200 525);
FORCEPROP 1 LAST VOLTAGE 50V
J 0
(1200 550);
DISPLAY 0.510638 (1200 550);
FORCEPROP 1 LAST VALUE 100NF
J 0
(1200 575);
DISPLAY 0.510638 (1200 575);
FORCEPROP 1 LAST TOLERANCE 10%
J 0
(1175 500);
DISPLAY 0.638298 (1175 500);
DISPLAY INVISIBLE (1175 500);
FORCEPROP 2 LAST CDS_LIB pure_quanta
J 0
(1125 550);
DISPLAY INVISIBLE (1125 550);
FORCEPROP 1 LAST PART_NUMBER CH4106K1B01
J 0
(1200 500);
DISPLAY 0.510638 (1200 500);
DISPLAY INVISIBLE (1200 500);
FORCEPROP 1 LAST PATH I39
J 0
(1175 700);
DISPLAY 0.978723 (1175 700);
PAINT WHITE (1175 700);
DISPLAY INVISIBLE (1175 700);
FORCEADD Q_RES..2
(675 -1650);
FORCEPROP 1 LAST LOCATION PR3945
J 0
(725 -1625);
DISPLAY 0.574468 (725 -1625);
FORCEPROP 0 LAST $SEC 1
J 0
(700 -1525);
DISPLAY INVISIBLE (700 -1525);
FORCEPROP 0 LAST CDS_SEC 1
J 0
(700 -1525);
DISPLAY INVISIBLE (700 -1525);
FORCEPROP 1 LASTPIN (675 -1550) $PN 1
J 0
(680 -1588);
DISPLAY 0.787234 (680 -1588);
PAINT MONO (680 -1588);
DISPLAY INVISIBLE (680 -1588);
FORCEPROP 1 LASTPIN (675 -1750) $PN 2
J 0
(680 -1740);
DISPLAY 0.787234 (680 -1740);
PAINT MONO (680 -1740);
DISPLAY INVISIBLE (680 -1740);
FORCEPROP 1 LAST VALUE 71.5K
J 0
(725 -1650);
DISPLAY 0.468085 (725 -1650);
FORCEPROP 1 LAST MATERIAL CHIP
J 0
(725 -1700);
DISPLAY 0.468085 (725 -1700);
PAINT RED (725 -1700);
FORCEPROP 1 LAST TOLERANCE 1%
J 0
(725 -1675);
DISPLAY 0.468085 (725 -1675);
FORCEPROP 1 LAST PACK_TYPE 0402LF
J 0
(725 -1750);
DISPLAY 0.468085 (725 -1750);
FORCEPROP 0 LAST ROOM E1S_P3V3_BOM2
J 0
(700 -1775);
DISPLAY 0.446809 (700 -1775);
PAINT RED (700 -1775);
FORCEPROP 1 LAST WATTAGE 1/16W
J 0
(700 -1675);
DISPLAY 0.723404 (700 -1675);
PAINT SKYBLUE (700 -1675);
DISPLAY INVISIBLE (700 -1675);
FORCEPROP 2 LAST CDS_LIB pure_quanta
J 0
(675 -1650);
DISPLAY INVISIBLE (675 -1650);
FORCEPROP 1 LAST PART_NUMBER CS37152FB05
J 0
(725 -1725);
DISPLAY 0.468085 (725 -1725);
DISPLAY INVISIBLE (725 -1725);
FORCEPROP 1 LAST PATH I4
J 0
(725 -1475);
DISPLAY 0.978723 (725 -1475);
PAINT WHITE (725 -1475);
DISPLAY INVISIBLE (725 -1475);
FORCEADD Q_RES..1
(1100 925);
FORCEPROP 1 LAST LOCATION PR3951
J 0
(1025 975);
DISPLAY 0.638298 (1025 975);
FORCEPROP 0 LAST $SEC 1
J 0
(1000 1000);
DISPLAY 0.680851 (1000 1000);
PAINT MONO (1000 1000);
DISPLAY INVISIBLE (1000 1000);
FORCEPROP 0 LAST CDS_SEC 1
J 0
(1050 1075);
DISPLAY INVISIBLE (1050 1075);
FORCEPROP 1 LASTPIN (1000 925) $PN 1
J 0
(1012 937);
DISPLAY 0.787234 (1012 937);
PAINT MONO (1012 937);
DISPLAY INVISIBLE (1012 937);
FORCEPROP 1 LASTPIN (1200 925) $PN 2
J 0
(1162 937);
DISPLAY 0.787234 (1162 937);
PAINT MONO (1162 937);
DISPLAY INVISIBLE (1162 937);
FORCEPROP 0 LAST ROOM E1S_P12V_MPS_MAM_BOM2
J 0
(1000 875);
DISPLAY 0.446809 (1000 875);
PAINT RED (1000 875);
FORCEPROP 1 LAST PACK_TYPE 0402LF
J 0
(1250 950);
DISPLAY 0.404255 (1250 950);
FORCEPROP 1 LAST VALUE 10K
J 2
(1075 900);
DISPLAY 0.510638 (1075 900);
FORCEPROP 1 LAST WATTAGE 1/16W
J 2
(1425 900);
DISPLAY 0.404255 (1425 900);
FORCEPROP 1 LAST TOLERANCE 1%
J 0
(1150 900);
DISPLAY 0.510638 (1150 900);
FORCEPROP 1 LAST MATERIAL CHIP
J 0
(1225 900);
DISPLAY 0.404255 (1225 900);
PAINT RED (1225 900);
FORCEPROP 2 LAST CDS_LIB pure_quanta
J 0
(1100 925);
DISPLAY INVISIBLE (1100 925);
FORCEPROP 1 LAST PART_NUMBER CS31002FB08
J 0
(1000 950);
DISPLAY 0.404255 (1000 950);
DISPLAY INVISIBLE (1000 950);
FORCEPROP 1 LAST PATH I40
J 0
(1050 1075);
DISPLAY 0.978723 (1050 1075);
PAINT WHITE (1050 1075);
DISPLAY INVISIBLE (1050 1075);
FORCEADD VCCAUX15..1
(1675 975);
FORCEPROP 3 LASTPIN (1675 925) SIG_NAME P3V3_AUX\g
J 0
(1685 935);
DISPLAY 0.659574 (1685 935);
PAINT MONO (1685 935);
DISPLAY INVISIBLE (1685 935);
FORCEPROP 1 LAST HDL_POWER P3V3_AUX
J 1
(1675 1000);
DISPLAY 0.574468 (1675 1000);
PAINT GREEN (1675 1000);
FORCEPROP 2 LAST CDS_LIB pure_quanta_power
J 0
(1675 975);
DISPLAY INVISIBLE (1675 975);
FORCEPROP 1 LAST PATH I41
J 0
(1725 1000);
DISPLAY 0.872340 (1725 1000);
PAINT AQUA (1725 1000);
DISPLAY INVISIBLE (1725 1000);
FORCEADD Q_RES..2
(1050 1400);
FORCEPROP 1 LAST LOCATION PR3950
J 0
(1100 1475);
DISPLAY 0.638298 (1100 1475);
FORCEPROP 0 LAST $SEC 1
J 0
(1100 1575);
DISPLAY 0.680851 (1100 1575);
PAINT MONO (1100 1575);
DISPLAY INVISIBLE (1100 1575);
FORCEPROP 0 LAST CDS_SEC 1
J 0
(1100 1575);
DISPLAY 1.021277 (1100 1575);
DISPLAY INVISIBLE (1100 1575);
FORCEPROP 1 LASTPIN (1050 1500) $PN 1
J 0
(1055 1462);
DISPLAY 0.787234 (1055 1462);
PAINT MONO (1055 1462);
FORCEPROP 1 LASTPIN (1050 1300) $PN 2
J 0
(1055 1310);
DISPLAY 0.787234 (1055 1310);
PAINT MONO (1055 1310);
FORCEPROP 1 LAST TOLERANCE 1%
J 0
(1100 1425);
DISPLAY 0.510638 (1100 1425);
FORCEPROP 1 LAST WATTAGE 1/16W
J 0
(1100 1400);
DISPLAY 0.510638 (1100 1400);
FORCEPROP 1 LAST VALUE 100
J 0
(1095 1450);
DISPLAY 0.510638 (1095 1450);
FORCEPROP 1 LAST MATERIAL EMPTY
J 0
(1100 1375);
DISPLAY 0.510638 (1100 1375);
PAINT RED (1100 1375);
FORCEPROP 1 LAST PACK_TYPE 0402LF
J 0
(1100 1325);
DISPLAY 0.510638 (1100 1325);
FORCEPROP 0 LAST ROOM E1S_P12V_MPS_MAM_BOM2
J 0
(1100 1525);
DISPLAY 0.553191 (1100 1525);
PAINT RED (1100 1525);
FORCEPROP 2 LAST CDS_LIB pure_quanta
J 0
(1050 1400);
DISPLAY INVISIBLE (1050 1400);
FORCEPROP 1 LAST PART_NUMBER CS11002FB07
J 0
(1100 1350);
DISPLAY 0.510638 (1100 1350);
DISPLAY INVISIBLE (1100 1350);
FORCEPROP 1 LAST PATH I42
J 0
(1100 1575);
DISPLAY 0.978723 (1100 1575);
PAINT WHITE (1100 1575);
DISPLAY INVISIBLE (1100 1575);
FORCEADD OFFPAGE..1
R 2
(1250 1175);
PAINT AQUA (1250 1175);
FORCEPROP 2 LAST $XR0 147 
J 0
(1436 1175);
DISPLAY 0.638298 (1436 1175);
PAINT MONO (1436 1175);
FORCEPROP 2 LAST CDS_LIB standard
J 2
(1250 1175);
DISPLAY INVISIBLE (1250 1175);
FORCEPROP 1 LAST OFFPAGE TRUE
J 2
(925 1050);
DISPLAY 0.872340 (925 1050);
PAINT AQUA (925 1050);
DISPLAY INVISIBLE (925 1050);
FORCEPROP 1 LAST COMMENT_BODY TRUE
J 2
(1125 1075);
DISPLAY 0.872340 (1125 1075);
PAINT GREEN (1125 1075);
DISPLAY INVISIBLE (1125 1075);
FORCEPROP 2 LAST PATH I43
J 0
(1450 1225);
DISPLAY 1.021277 (1450 1225);
DISPLAY INVISIBLE (1450 1225);
FORCEADD OFFPAGE..2
(1325 1775);
PAINT AQUA (1325 1775);
FORCEPROP 2 LAST $XR0 146 
J 0
(1514 1775);
DISPLAY 0.638298 (1514 1775);
PAINT MONO (1514 1775);
FORCEPROP 2 LAST $XR1 81 
J 0
(1514 1739);
DISPLAY 0.638298 (1514 1739);
PAINT MONO (1514 1739);
FORCEPROP 2 LAST CDS_LIB standard
J 0
(1325 1775);
DISPLAY INVISIBLE (1325 1775);
FORCEPROP 1 LAST OFFPAGE TRUE
J 0
(1650 1650);
DISPLAY 0.872340 (1650 1650);
PAINT AQUA (1650 1650);
DISPLAY INVISIBLE (1650 1650);
FORCEPROP 1 LAST COMMENT_BODY TRUE
J 0
(1280 1680);
DISPLAY 0.872340 (1280 1680);
PAINT GREEN (1280 1680);
DISPLAY INVISIBLE (1280 1680);
FORCEPROP 2 LAST PATH I44
J 0
(1525 1825);
DISPLAY 1.021277 (1525 1825);
DISPLAY INVISIBLE (1525 1825);
FORCEADD Q_RES..2
(1650 1400);
FORCEPROP 1 LAST LOCATION PR3952
J 0
(1700 1450);
DISPLAY 0.574468 (1700 1450);
FORCEPROP 0 LAST $SEC 1
J 0
(1675 1525);
DISPLAY 0.680851 (1675 1525);
PAINT MONO (1675 1525);
DISPLAY INVISIBLE (1675 1525);
FORCEPROP 0 LAST CDS_SEC 1
J 0
(1675 1525);
DISPLAY 1.021277 (1675 1525);
DISPLAY INVISIBLE (1675 1525);
FORCEPROP 1 LASTPIN (1650 1500) $PN 1
J 0
(1655 1462);
DISPLAY 0.787234 (1655 1462);
FORCEPROP 1 LASTPIN (1650 1300) $PN 2
J 0
(1655 1310);
DISPLAY 0.787234 (1655 1310);
FORCEPROP 0 LAST ROOM E1S_P12V_MPS_MAM_BOM2
J 0
(1700 1500);
DISPLAY 0.446809 (1700 1500);
PAINT RED (1700 1500);
FORCEPROP 1 LAST TOLERANCE 1%
J 0
(1700 1400);
DISPLAY 0.468085 (1700 1400);
FORCEPROP 1 LAST PACK_TYPE 0402LF
J 0
(1700 1325);
DISPLAY 0.468085 (1700 1325);
FORCEPROP 1 LAST VALUE 71.5K
J 0
(1700 1425);
DISPLAY 0.468085 (1700 1425);
FORCEPROP 1 LAST MATERIAL EMPTY
J 0
(1700 1375);
DISPLAY 0.574468 (1700 1375);
PAINT RED (1700 1375);
FORCEPROP 2 LAST CDS_LIB pure_quanta
J 0
(1650 1400);
DISPLAY INVISIBLE (1650 1400);
FORCEPROP 1 LAST WATTAGE 1/16W
J 0
(1675 1375);
DISPLAY 0.723404 (1675 1375);
PAINT SKYBLUE (1675 1375);
DISPLAY INVISIBLE (1675 1375);
FORCEPROP 1 LAST PART_NUMBER CS37152FB05
J 0
(1700 1350);
DISPLAY 0.468085 (1700 1350);
DISPLAY INVISIBLE (1700 1350);
FORCEPROP 1 LAST PATH I45
J 0
(1700 1575);
DISPLAY 0.978723 (1700 1575);
PAINT WHITE (1700 1575);
DISPLAY INVISIBLE (1700 1575);
FORCEADD VCCAUX15..1
(525 2200);
FORCEPROP 3 LASTPIN (525 2150) SIG_NAME P3V3_AUX\g
J 0
(535 2160);
DISPLAY 0.659574 (535 2160);
PAINT MONO (535 2160);
DISPLAY INVISIBLE (535 2160);
FORCEPROP 1 LAST HDL_POWER P3V3_AUX
J 1
(525 2250);
DISPLAY 0.723404 (525 2250);
PAINT GREEN (525 2250);
FORCEPROP 2 LAST CDS_LIB pure_quanta_power
J 0
(525 2200);
DISPLAY INVISIBLE (525 2200);
FORCEPROP 1 LAST PATH I46
J 0
(575 2225);
DISPLAY 0.872340 (575 2225);
PAINT AQUA (575 2225);
DISPLAY INVISIBLE (575 2225);
FORCEADD Q_RES..1
(2475 225);
FORCEPROP 1 LAST LOCATION R3956
J 0
(2425 275);
DISPLAY 0.978723 (2425 275);
FORCEPROP 0 LAST $SEC 1
J 0
(2425 325);
DISPLAY 0.680851 (2425 325);
PAINT MONO (2425 325);
DISPLAY INVISIBLE (2425 325);
FORCEPROP 0 LAST CDS_SEC 1
J 0
(2425 325);
DISPLAY 1.021277 (2425 325);
DISPLAY INVISIBLE (2425 325);
FORCEPROP 1 LASTPIN (2375 225) $PN 1
J 0
(2387 237);
DISPLAY 0.787234 (2387 237);
PAINT MONO (2387 237);
FORCEPROP 1 LASTPIN (2575 225) $PN 2
J 0
(2537 237);
DISPLAY 0.787234 (2537 237);
PAINT MONO (2537 237);
FORCEPROP 1 LAST MATERIAL EMPTY
J 0
(2250 225);
DISPLAY 0.595745 (2250 225);
PAINT RED (2250 225);
FORCEPROP 0 LAST ROOM E1S_P12V_MPS_TIC_BOM3
J 0
(2200 125);
DISPLAY 0.553191 (2200 125);
PAINT RED (2200 125);
FORCEPROP 1 LAST VALUE 0
J 2
(2625 225);
DISPLAY 0.595745 (2625 225);
FORCEPROP 1 LAST PACK_TYPE 0402LF
J 0
(2625 175);
DISPLAY 0.595745 (2625 175);
FORCEPROP 1 LAST WATTAGE 1/16W
J 2
(2275 175);
DISPLAY 0.595745 (2275 175);
FORCEPROP 1 LAST TOLERANCE 5%
J 0
(2650 225);
DISPLAY 0.595745 (2650 225);
FORCEPROP 2 LAST CDS_LIB pure_quanta
J 0
(2475 225);
DISPLAY INVISIBLE (2475 225);
FORCEPROP 1 LAST PART_NUMBER CS00002JB13
J 0
(2300 175);
DISPLAY 0.595745 (2300 175);
DISPLAY INVISIBLE (2300 175);
FORCEPROP 1 LAST PATH I47
J 0
(2425 375);
DISPLAY 0.978723 (2425 375);
PAINT WHITE (2425 375);
DISPLAY INVISIBLE (2425 375);
FORCEADD Q_RES..1
(2475 400);
FORCEPROP 1 LAST LOCATION R3955
J 0
(2425 450);
DISPLAY 0.978723 (2425 450);
FORCEPROP 0 LAST $SEC 1
J 0
(2425 500);
DISPLAY 0.680851 (2425 500);
PAINT MONO (2425 500);
DISPLAY INVISIBLE (2425 500);
FORCEPROP 0 LAST CDS_SEC 1
J 0
(2425 500);
DISPLAY 1.021277 (2425 500);
DISPLAY INVISIBLE (2425 500);
FORCEPROP 1 LASTPIN (2375 400) $PN 1
J 0
(2387 412);
DISPLAY 0.787234 (2387 412);
PAINT MONO (2387 412);
FORCEPROP 1 LASTPIN (2575 400) $PN 2
J 0
(2537 412);
DISPLAY 0.787234 (2537 412);
PAINT MONO (2537 412);
FORCEPROP 1 LAST WATTAGE 1/16W
J 2
(2275 350);
DISPLAY 0.595745 (2275 350);
FORCEPROP 1 LAST PACK_TYPE 0402LF
J 0
(2625 350);
DISPLAY 0.595745 (2625 350);
FORCEPROP 1 LAST MATERIAL CHIP
J 0
(2250 400);
DISPLAY 0.595745 (2250 400);
PAINT RED (2250 400);
FORCEPROP 0 LAST ROOM E1S_P12V_MPS_MAM_BOM2
J 0
(2425 525);
DISPLAY 0.553191 (2425 525);
PAINT RED (2425 525);
FORCEPROP 1 LAST VALUE 0
J 2
(2625 400);
DISPLAY 0.595745 (2625 400);
FORCEPROP 1 LAST TOLERANCE 5%
J 0
(2650 400);
DISPLAY 0.595745 (2650 400);
FORCEPROP 2 LAST CDS_LIB pure_quanta
J 0
(2475 400);
DISPLAY INVISIBLE (2475 400);
FORCEPROP 1 LAST PART_NUMBER CS00002JB13
J 0
(2300 350);
DISPLAY 0.595745 (2300 350);
DISPLAY INVISIBLE (2300 350);
FORCEPROP 1 LAST PATH I48
J 0
(2425 550);
DISPLAY 0.978723 (2425 550);
PAINT WHITE (2425 550);
DISPLAY INVISIBLE (2425 550);
FORCEADD Q_RES..2
(2050 900);
FORCEPROP 1 LAST LOCATION PR3954
J 0
(2100 975);
DISPLAY 0.638298 (2100 975);
FORCEPROP 0 LAST $SEC 1
J 0
(2100 1075);
DISPLAY INVISIBLE (2100 1075);
FORCEPROP 0 LAST CDS_SEC 1
J 0
(2100 1075);
DISPLAY INVISIBLE (2100 1075);
FORCEPROP 1 LASTPIN (2050 1000) $PN 1
J 0
(2055 962);
DISPLAY 0.787234 (2055 962);
PAINT MONO (2055 962);
DISPLAY INVISIBLE (2055 962);
FORCEPROP 1 LASTPIN (2050 800) $PN 2
J 0
(2055 810);
DISPLAY 0.787234 (2055 810);
PAINT MONO (2055 810);
DISPLAY INVISIBLE (2055 810);
FORCEPROP 1 LAST PACK_TYPE 0402LF
J 0
(2100 825);
DISPLAY 0.510638 (2100 825);
FORCEPROP 1 LAST TOLERANCE 1%
J 0
(2100 925);
DISPLAY 0.510638 (2100 925);
FORCEPROP 1 LAST VALUE 10K
J 0
(2100 950);
DISPLAY 0.510638 (2100 950);
FORCEPROP 1 LAST MATERIAL CHIP
J 0
(2100 875);
DISPLAY 0.510638 (2100 875);
PAINT RED (2100 875);
FORCEPROP 1 LAST WATTAGE 1/16W
J 0
(2100 900);
DISPLAY 0.510638 (2100 900);
FORCEPROP 0 LAST ROOM E1S_P12V_MPS_MAM_BOM2
J 0
(2100 1025);
DISPLAY 0.446809 (2100 1025);
PAINT RED (2100 1025);
FORCEPROP 2 LAST CDS_LIB pure_quanta
J 0
(2050 900);
DISPLAY INVISIBLE (2050 900);
FORCEPROP 1 LAST PART_NUMBER CS31002FB08
J 0
(2100 850);
DISPLAY 0.510638 (2100 850);
DISPLAY INVISIBLE (2100 850);
FORCEPROP 1 LAST PATH I49
J 0
(2100 1075);
DISPLAY 0.978723 (2100 1075);
PAINT WHITE (2100 1075);
DISPLAY INVISIBLE (2100 1075);
FORCEADD Q_RES..1
(750 -1350);
FORCEPROP 1 LAST LOCATION R3946
J 0
(525 -1350);
DISPLAY 0.787234 (525 -1350);
FORCEPROP 0 LAST $SEC 1
J 0
(525 -1300);
DISPLAY 0.680851 (525 -1300);
PAINT MONO (525 -1300);
DISPLAY INVISIBLE (525 -1300);
FORCEPROP 0 LAST CDS_SEC 1
J 0
(525 -1300);
DISPLAY 1.021277 (525 -1300);
DISPLAY INVISIBLE (525 -1300);
FORCEPROP 1 LASTPIN (650 -1350) $PN 1
J 0
(662 -1338);
DISPLAY 0.787234 (662 -1338);
PAINT MONO (662 -1338);
FORCEPROP 1 LASTPIN (850 -1350) $PN 2
J 0
(812 -1338);
DISPLAY 0.787234 (812 -1338);
PAINT MONO (812 -1338);
FORCEPROP 1 LAST WATTAGE 1/16W
J 2
(925 -1425);
DISPLAY 0.510638 (925 -1425);
FORCEPROP 1 LAST VALUE 0
J 2
(900 -1350);
DISPLAY 0.510638 (900 -1350);
FORCEPROP 1 LAST MATERIAL CHIP
J 0
(675 -1425);
DISPLAY 0.510638 (675 -1425);
PAINT RED (675 -1425);
FORCEPROP 1 LAST TOLERANCE 5%
J 0
(925 -1350);
DISPLAY 0.510638 (925 -1350);
FORCEPROP 1 LAST PACK_TYPE 0402LF
J 0
(1000 -1350);
DISPLAY 0.510638 (1000 -1350);
FORCEPROP 0 LAST ROOM E1S_P3V3_BOM2
J 0
(525 -1250);
DISPLAY 0.680851 (525 -1250);
PAINT RED (525 -1250);
FORCEPROP 2 LAST CDS_LIB pure_quanta
J 0
(750 -1350);
DISPLAY INVISIBLE (750 -1350);
FORCEPROP 1 LAST PART_NUMBER CS00002JB13
J 0
(675 -1400);
DISPLAY 0.510638 (675 -1400);
DISPLAY INVISIBLE (675 -1400);
FORCEPROP 1 LAST PATH I5
J 0
(700 -1200);
DISPLAY 0.978723 (700 -1200);
PAINT WHITE (700 -1200);
DISPLAY INVISIBLE (700 -1200);
FORCEADD GND..1
(2250 575);
FORCEPROP 3 LASTPIN (2250 625) SIG_NAME GND\g
J 0
(2260 635);
DISPLAY 0.659574 (2260 635);
PAINT MONO (2260 635);
DISPLAY INVISIBLE (2260 635);
FORCEPROP 2 LAST CDS_LIB pure_quanta_power
J 0
(2250 575);
DISPLAY INVISIBLE (2250 575);
FORCEPROP 1 LAST SIZE 1B
J 0
(2325 525);
DISPLAY 0.872340 (2325 525);
PAINT GREEN (2325 525);
DISPLAY INVISIBLE (2325 525);
FORCEPROP 1 LAST HDL_POWER GND
J 0
(2250 725);
DISPLAY 0.872340 (2250 725);
PAINT GREEN (2250 725);
DISPLAY INVISIBLE (2250 725);
FORCEPROP 1 LAST PATH I50
J 0
(2325 575);
DISPLAY 0.872340 (2325 575);
PAINT AQUA (2325 575);
DISPLAY INVISIBLE (2325 575);
FORCEADD Q_CAP..1
(2575 900);
FORCEPROP 1 LAST LOCATION PC2205
J 0
(2650 950);
DISPLAY 0.638298 (2650 950);
FORCEPROP 0 LAST $SEC 1
J 0
(2650 1050);
DISPLAY INVISIBLE (2650 1050);
FORCEPROP 0 LAST CDS_SEC 1
J 0
(2650 1050);
DISPLAY INVISIBLE (2650 1050);
FORCEPROP 1 LASTPIN (2575 1000) $PN 1
J 0
(2585 980);
DISPLAY 0.787234 (2585 980);
PAINT MONO (2585 980);
DISPLAY INVISIBLE (2585 980);
FORCEPROP 1 LASTPIN (2575 800) $PN 2
J 0
(2585 780);
DISPLAY 0.787234 (2585 780);
PAINT MONO (2585 780);
DISPLAY INVISIBLE (2585 780);
FORCEPROP 0 LAST ROOM E1S_P12V_MPS_MAM_BOM2
J 0
(2650 1000);
DISPLAY 0.446809 (2650 1000);
PAINT RED (2650 1000);
FORCEPROP 1 LAST PACK_TYPE C0603
J 0
(2650 800);
DISPLAY 0.510638 (2650 800);
FORCEPROP 1 LAST VOLTAGE 16V
J 0
(2650 900);
DISPLAY 0.510638 (2650 900);
FORCEPROP 1 LAST TOLERANCE 20%
J 0
(2650 875);
DISPLAY 0.510638 (2650 875);
FORCEPROP 1 LAST VALUE 2.2UF
J 0
(2650 925);
DISPLAY 0.510638 (2650 925);
FORCEPROP 1 LAST MATERIAL X7R
J 0
(2650 850);
DISPLAY 0.510638 (2650 850);
PAINT RED (2650 850);
FORCEPROP 2 LAST CDS_LIB pure_quanta
J 0
(2575 900);
DISPLAY INVISIBLE (2575 900);
FORCEPROP 1 LAST PART_NUMBER CH5223M1900
J 0
(2650 825);
DISPLAY 0.510638 (2650 825);
DISPLAY INVISIBLE (2650 825);
FORCEPROP 1 LAST PATH I51
J 0
(2625 1050);
DISPLAY 0.978723 (2625 1050);
PAINT WHITE (2625 1050);
DISPLAY INVISIBLE (2625 1050);
FORCEADD Q_RES..2
(2050 1325);
FORCEPROP 1 LAST LOCATION PR3953
J 0
(2100 1375);
DISPLAY 0.510638 (2100 1375);
FORCEPROP 0 LAST $SEC 1
J 0
(2100 1500);
DISPLAY INVISIBLE (2100 1500);
FORCEPROP 0 LAST CDS_SEC 1
J 0
(2100 1500);
DISPLAY INVISIBLE (2100 1500);
FORCEPROP 1 LASTPIN (2050 1425) $PN 1
J 0
(2055 1387);
DISPLAY 0.787234 (2055 1387);
PAINT MONO (2055 1387);
DISPLAY INVISIBLE (2055 1387);
FORCEPROP 1 LASTPIN (2050 1225) $PN 2
J 0
(2055 1235);
DISPLAY 0.787234 (2055 1235);
PAINT MONO (2055 1235);
DISPLAY INVISIBLE (2055 1235);
FORCEPROP 1 LAST VALUE 120K
J 0
(2100 1350);
DISPLAY 0.510638 (2100 1350);
FORCEPROP 1 LAST TOLERANCE 1%
J 0
(2100 1325);
DISPLAY 0.510638 (2100 1325);
FORCEPROP 1 LAST PACK_TYPE 0402LF
J 0
(2100 1225);
DISPLAY 0.510638 (2100 1225);
FORCEPROP 1 LAST MATERIAL CHIP
J 0
(2100 1275);
DISPLAY 0.510638 (2100 1275);
PAINT RED (2100 1275);
FORCEPROP 1 LAST WATTAGE 1/16W
J 0
(2100 1300);
DISPLAY 0.510638 (2100 1300);
FORCEPROP 0 LAST ROOM E1S_P12V_MPS_MAM_BOM2
J 0
(2100 1400);
DISPLAY 0.446809 (2100 1400);
PAINT RED (2100 1400);
FORCEPROP 2 LAST CDS_LIB pure_quanta
J 0
(2050 1325);
DISPLAY INVISIBLE (2050 1325);
FORCEPROP 1 LAST PART_NUMBER CS41202FB05
J 0
(2100 1250);
DISPLAY 0.510638 (2100 1250);
DISPLAY INVISIBLE (2100 1250);
FORCEPROP 1 LAST PATH I52
J 0
(2100 1500);
DISPLAY 0.978723 (2100 1500);
PAINT WHITE (2100 1500);
DISPLAY INVISIBLE (2100 1500);
FORCEADD UNIVERSAL_POWER..1
(2475 1625);
FORCEPROP 3 LASTPIN (2475 1575) SIG_NAME P12V_AUX\g
J 0
(2485 1585);
DISPLAY 0.659574 (2485 1585);
PAINT MONO (2485 1585);
DISPLAY INVISIBLE (2485 1585);
FORCEPROP 1 LAST HDL_POWER P12V_AUX
J 1
(2475 1675);
DISPLAY 0.702128 (2475 1675);
PAINT GREEN (2475 1675);
FORCEPROP 2 LAST CDS_LIB pure_quanta_power
J 0
(2475 1625);
DISPLAY INVISIBLE (2475 1625);
FORCEPROP 1 LAST PATH I53
J 0
(2525 1650);
DISPLAY 0.872340 (2525 1650);
PAINT AQUA (2525 1650);
DISPLAY INVISIBLE (2525 1650);
FORCEADD Q_RES..2
(2575 1325);
FORCEPROP 1 LAST LOCATION PR3957
J 0
(2650 1375);
DISPLAY 0.510638 (2650 1375);
FORCEPROP 0 LAST $SEC 1
J 0
(2625 1500);
DISPLAY 0.680851 (2625 1500);
PAINT MONO (2625 1500);
DISPLAY INVISIBLE (2625 1500);
FORCEPROP 0 LAST CDS_SEC 1
J 0
(2625 1500);
DISPLAY 1.021277 (2625 1500);
DISPLAY INVISIBLE (2625 1500);
FORCEPROP 1 LASTPIN (2575 1425) $PN 1
J 0
(2580 1387);
DISPLAY 0.787234 (2580 1387);
PAINT MONO (2580 1387);
FORCEPROP 1 LASTPIN (2575 1225) $PN 2
J 0
(2580 1235);
DISPLAY 0.787234 (2580 1235);
PAINT MONO (2580 1235);
FORCEPROP 1 LAST MATERIAL CHIP
J 0
(2650 1275);
DISPLAY 0.510638 (2650 1275);
PAINT RED (2650 1275);
FORCEPROP 1 LAST WATTAGE 1/10W
J 0
(2650 1300);
DISPLAY 0.510638 (2650 1300);
FORCEPROP 1 LAST TOLERANCE 1%
J 0
(2650 1325);
DISPLAY 0.510638 (2650 1325);
FORCEPROP 1 LAST PACK_TYPE 0603LF
J 0
(2650 1225);
DISPLAY 0.510638 (2650 1225);
FORCEPROP 1 LAST VALUE 49.9
J 0
(2650 1350);
DISPLAY 0.510638 (2650 1350);
FORCEPROP 0 LAST ROOM E1S_P12V_MPS_MAM_BOM2
J 0
(2650 1400);
DISPLAY 0.446809 (2650 1400);
PAINT RED (2650 1400);
FORCEPROP 2 LAST CDS_LIB pure_quanta
J 0
(2575 1325);
DISPLAY INVISIBLE (2575 1325);
FORCEPROP 1 LAST PART_NUMBER CS04993F909
J 0
(2650 1250);
DISPLAY 0.510638 (2650 1250);
DISPLAY INVISIBLE (2650 1250);
FORCEPROP 1 LAST PATH I54
J 0
(2625 1500);
DISPLAY 0.978723 (2625 1500);
PAINT WHITE (2625 1500);
DISPLAY INVISIBLE (2625 1500);
FORCEADD GND..1
(2925 1475);
FORCEPROP 3 LASTPIN (2925 1525) SIG_NAME GND\g
J 0
(2935 1535);
DISPLAY 0.659574 (2935 1535);
PAINT MONO (2935 1535);
DISPLAY INVISIBLE (2935 1535);
FORCEPROP 1 LAST SIZE 1B
J 0
(3000 1425);
DISPLAY 0.872340 (3000 1425);
PAINT GREEN (3000 1425);
DISPLAY INVISIBLE (3000 1425);
FORCEPROP 2 LAST CDS_LIB pure_quanta_power
J 0
(2925 1475);
DISPLAY INVISIBLE (2925 1475);
FORCEPROP 1 LAST HDL_POWER GND
J 0
(2925 1625);
DISPLAY 0.872340 (2925 1625);
PAINT GREEN (2925 1625);
DISPLAY INVISIBLE (2925 1625);
FORCEPROP 1 LAST PATH I55
J 0
(3000 1475);
DISPLAY 0.872340 (3000 1475);
PAINT AQUA (3000 1475);
DISPLAY INVISIBLE (3000 1475);
FORCEADD Q_CAP..1
R 2
(2925 1750);
FORCEPROP 1 LAST LOCATION PC2206
J 0
(3000 1800);
DISPLAY 0.638298 (3000 1800);
FORCEPROP 0 LAST $SEC 1
J 0
(3275 1900);
DISPLAY 0.680851 (3275 1900);
PAINT MONO (3275 1900);
DISPLAY INVISIBLE (3275 1900);
FORCEPROP 0 LAST CDS_SEC 1
J 0
(3275 1900);
DISPLAY 1.021277 (3275 1900);
DISPLAY INVISIBLE (3275 1900);
FORCEPROP 1 LASTPIN (2925 1850) $PN 1
J 2
(2915 1830);
DISPLAY 0.787234 (2915 1830);
PAINT MONO (2915 1830);
FORCEPROP 1 LASTPIN (2925 1650) $PN 2
J 2
(2915 1630);
DISPLAY 0.787234 (2915 1630);
PAINT MONO (2915 1630);
FORCEPROP 1 LAST TOLERANCE 10%
J 0
(3000 1725);
DISPLAY 0.510638 (3000 1725);
FORCEPROP 1 LAST MATERIAL X7R
J 0
(3000 1700);
DISPLAY 0.510638 (3000 1700);
PAINT RED (3000 1700);
FORCEPROP 1 LAST PACK_TYPE 0402
J 0
(3000 1650);
DISPLAY 0.510638 (3000 1650);
FORCEPROP 1 LAST VOLTAGE 25V
J 0
(3000 1750);
DISPLAY 0.510638 (3000 1750);
FORCEPROP 0 LAST ROOM E1S_P12V_MPS_MAM_BOM2
J 0
(3000 1900);
DISPLAY 0.680851 (3000 1900);
PAINT RED (3000 1900);
FORCEPROP 1 LAST VALUE 0.1UF
J 0
(3000 1775);
DISPLAY 0.510638 (3000 1775);
FORCEPROP 2 LAST CDS_LIB pure_quanta
J 0
(2925 1750);
DISPLAY INVISIBLE (2925 1750);
FORCEPROP 1 LAST PART_NUMBER CH4104K1B00
J 0
(3000 1675);
DISPLAY 0.510638 (3000 1675);
DISPLAY INVISIBLE (3000 1675);
FORCEPROP 1 LAST PATH I56
J 2
(2875 1900);
DISPLAY 0.978723 (2875 1900);
PAINT WHITE (2875 1900);
DISPLAY INVISIBLE (2875 1900);
FORCEADD UNIVERSAL_POWER..1
R 2
(2925 2025);
FORCEPROP 3 LASTPIN (2925 1975) SIG_NAME P12V_E1S_0\g
J 0
(2935 1985);
DISPLAY 0.659574 (2935 1985);
PAINT MONO (2935 1985);
DISPLAY INVISIBLE (2935 1985);
FORCEPROP 1 LAST HDL_POWER P12V_E1S_0
J 1
(2925 2075);
DISPLAY 0.723404 (2925 2075);
PAINT GREEN (2925 2075);
FORCEPROP 2 LAST CDS_LIB pure_quanta_power
J 0
(2925 2025);
DISPLAY INVISIBLE (2925 2025);
FORCEPROP 1 LAST PATH I57
J 2
(2875 2050);
DISPLAY 0.872340 (2875 2050);
PAINT AQUA (2875 2050);
DISPLAY INVISIBLE (2875 2050);
FORCEADD OFFPAGE..2
(3225 1050);
PAINT AQUA (3225 1050);
FORCEPROP 2 LAST $XR0 147 
J 0
(3414 1050);
DISPLAY 0.638298 (3414 1050);
PAINT MONO (3414 1050);
FORCEPROP 2 LAST CDS_LIB standard
J 0
(3225 1050);
DISPLAY INVISIBLE (3225 1050);
FORCEPROP 1 LAST OFFPAGE TRUE
J 0
(3550 925);
DISPLAY 0.872340 (3550 925);
PAINT AQUA (3550 925);
DISPLAY INVISIBLE (3550 925);
FORCEPROP 1 LAST COMMENT_BODY TRUE
J 0
(3180 955);
DISPLAY 0.872340 (3180 955);
PAINT GREEN (3180 955);
DISPLAY INVISIBLE (3180 955);
FORCEPROP 2 LAST PATH I58
J 0
(3425 1100);
DISPLAY 1.021277 (3425 1100);
DISPLAY INVISIBLE (3425 1100);
FORCEADD OFFPAGE..2
(3700 225);
PAINT AQUA (3700 225);
FORCEPROP 2 LAST $XR0 258 
J 0
(3889 225);
DISPLAY 0.638298 (3889 225);
PAINT MONO (3889 225);
FORCEPROP 2 LAST CDS_LIB standard
J 0
(3700 225);
DISPLAY INVISIBLE (3700 225);
FORCEPROP 1 LAST OFFPAGE TRUE
J 0
(4025 100);
DISPLAY 0.872340 (4025 100);
PAINT AQUA (4025 100);
DISPLAY INVISIBLE (4025 100);
FORCEPROP 1 LAST COMMENT_BODY TRUE
J 0
(3655 130);
DISPLAY 0.872340 (3655 130);
PAINT GREEN (3655 130);
DISPLAY INVISIBLE (3655 130);
FORCEPROP 2 LAST PATH I59
J 0
(3900 275);
DISPLAY 1.021277 (3900 275);
DISPLAY INVISIBLE (3900 275);
FORCEADD Q_RES..1
R 1
(1000 -1700);
FORCEPROP 1 LAST LOCATION PR3947
J 0
(1050 -1650);
DISPLAY 0.638298 (1050 -1650);
FORCEPROP 0 LAST $SEC 1
R 1
J 0
(1025 -1625);
DISPLAY INVISIBLE (1025 -1625);
FORCEPROP 0 LAST CDS_SEC 1
R 1
J 0
(1025 -1625);
DISPLAY INVISIBLE (1025 -1625);
FORCEPROP 1 LASTPIN (1000 -1800) $PN 1
R 1
J 0
(988 -1788);
DISPLAY 0.787234 (988 -1788);
PAINT MONO (988 -1788);
DISPLAY INVISIBLE (988 -1788);
FORCEPROP 1 LASTPIN (1000 -1600) $PN 2
R 1
J 0
(988 -1638);
DISPLAY 0.787234 (988 -1638);
PAINT MONO (988 -1638);
DISPLAY INVISIBLE (988 -1638);
FORCEPROP 1 LAST PACK_TYPE 0402LF
J 0
(1050 -1775);
DISPLAY 0.510638 (1050 -1775);
FORCEPROP 1 LAST TOLERANCE 1%
J 0
(1050 -1700);
DISPLAY 0.510638 (1050 -1700);
FORCEPROP 1 LAST VALUE 2.8K
J 0
(1050 -1675);
DISPLAY 0.510638 (1050 -1675);
FORCEPROP 1 LAST MATERIAL CHIP
J 0
(1050 -1725);
DISPLAY 0.510638 (1050 -1725);
PAINT RED (1050 -1725);
FORCEPROP 0 LAST ROOM E1S_P3V3_BOM2
J 0
(1050 -1825);
DISPLAY 0.680851 (1050 -1825);
PAINT RED (1050 -1825);
FORCEPROP 1 LAST WATTAGE 1/16W
R 1
J 2
(1150 -1725);
DISPLAY 0.978723 (1150 -1725);
DISPLAY INVISIBLE (1150 -1725);
FORCEPROP 2 LAST CDS_LIB pure_quanta
R 1
J 0
(1000 -1700);
DISPLAY INVISIBLE (1000 -1700);
FORCEPROP 1 LAST PART_NUMBER CS22802FB04
J 0
(1050 -1750);
DISPLAY 0.510638 (1050 -1750);
DISPLAY INVISIBLE (1050 -1750);
FORCEPROP 1 LAST PATH I6
R 1
J 0
(850 -1750);
DISPLAY 0.978723 (850 -1750);
PAINT WHITE (850 -1750);
DISPLAY INVISIBLE (850 -1750);
FORCEADD OFFPAGE..2
(3725 400);
PAINT AQUA (3725 400);
FORCEPROP 2 LAST $XR0 258 
J 0
(3914 400);
DISPLAY 0.638298 (3914 400);
PAINT MONO (3914 400);
FORCEPROP 2 LAST CDS_LIB standard
J 0
(3725 400);
DISPLAY INVISIBLE (3725 400);
FORCEPROP 1 LAST OFFPAGE TRUE
J 0
(4050 275);
DISPLAY 0.872340 (4050 275);
PAINT AQUA (4050 275);
DISPLAY INVISIBLE (4050 275);
FORCEPROP 1 LAST COMMENT_BODY TRUE
J 0
(3680 305);
DISPLAY 0.872340 (3680 305);
PAINT GREEN (3680 305);
DISPLAY INVISIBLE (3680 305);
FORCEPROP 2 LAST PATH I60
J 0
(3925 450);
DISPLAY 1.021277 (3925 450);
DISPLAY INVISIBLE (3925 450);
FORCEADD UNIVERSAL_GND..1
(-4000 -2600);
FORCEPROP 3 LASTPIN (-4000 -2550) SIG_NAME GND\g
J 0
(-3990 -2540);
DISPLAY 0.659574 (-3990 -2540);
PAINT MONO (-3990 -2540);
DISPLAY INVISIBLE (-3990 -2540);
FORCEPROP 2 LAST CDS_LIB pure_quanta_power
J 0
(-4000 -2600);
DISPLAY INVISIBLE (-4000 -2600);
FORCEPROP 1 LAST HDL_POWER GND
J 1
(-3975 -2675);
DISPLAY 0.872340 (-3975 -2675);
PAINT GREEN (-3975 -2675);
DISPLAY INVISIBLE (-3975 -2675);
FORCEPROP 1 LAST PATH I63
J 0
(-3925 -2600);
DISPLAY 0.872340 (-3925 -2600);
PAINT AQUA (-3925 -2600);
DISPLAY INVISIBLE (-3925 -2600);
FORCEADD Q_CAP..1
R 2
(-4000 -2250);
FORCEPROP 1 LAST LOCATION C8010
J 2
(-4050 -2150);
DISPLAY 0.787234 (-4050 -2150);
FORCEPROP 0 LAST $SEC 1
J 0
(-4050 -2100);
DISPLAY 0.680851 (-4050 -2100);
PAINT MONO (-4050 -2100);
DISPLAY INVISIBLE (-4050 -2100);
FORCEPROP 0 LAST CDS_SEC 1
J 0
(-4050 -2100);
DISPLAY 0.680851 (-4050 -2100);
DISPLAY INVISIBLE (-4050 -2100);
FORCEPROP 1 LASTPIN (-4000 -2150) $PN 1
J 2
(-4010 -2170);
DISPLAY 0.787234 (-4010 -2170);
PAINT MONO (-4010 -2170);
FORCEPROP 1 LASTPIN (-4000 -2350) $PN 2
J 2
(-4010 -2370);
DISPLAY 0.787234 (-4010 -2370);
PAINT MONO (-4010 -2370);
FORCEPROP 1 LAST TOLERANCE 10%
J 2
(-4050 -2300);
DISPLAY 0.787234 (-4050 -2300);
FORCEPROP 1 LAST VALUE 0.1UF
J 2
(-4050 -2200);
DISPLAY 0.787234 (-4050 -2200);
FORCEPROP 1 LAST VOLTAGE 25V
J 2
(-4050 -2250);
DISPLAY 0.787234 (-4050 -2250);
FORCEPROP 1 LAST MATERIAL X7R
J 2
(-4050 -2350);
DISPLAY 0.787234 (-4050 -2350);
PAINT RED (-4050 -2350);
FORCEPROP 1 LAST PACK_TYPE 0402
J 2
(-4050 -2450);
DISPLAY 0.787234 (-4050 -2450);
FORCEPROP 0 LAST ROOM E1S_P3V3_BOM2
J 0
(-4450 -2500);
DISPLAY 0.680851 (-4450 -2500);
PAINT RED (-4450 -2500);
FORCEPROP 2 LAST CDS_LIB pure_quanta
J 0
(-4000 -2250);
DISPLAY INVISIBLE (-4000 -2250);
FORCEPROP 1 LAST PART_NUMBER CH4104K1B00
J 2
(-4050 -2400);
DISPLAY 0.787234 (-4050 -2400);
DISPLAY INVISIBLE (-4050 -2400);
FORCEPROP 1 LAST PATH I64
J 2
(-4050 -2100);
DISPLAY 0.978723 (-4050 -2100);
PAINT WHITE (-4050 -2100);
DISPLAY INVISIBLE (-4050 -2100);
FORCEADD APX80929SAG7..1
R 2
(-3325 -2000);
FORCEPROP 1 LAST LOCATION U8003
J 2
(-3100 -1681);
DISPLAY 0.723404 (-3100 -1681);
PAINT GREEN (-3100 -1681);
FORCEPROP 0 LAST $SEC 1
J 0
(-3100 -1525);
DISPLAY 0.680851 (-3100 -1525);
PAINT MONO (-3100 -1525);
DISPLAY INVISIBLE (-3100 -1525);
FORCEPROP 0 LAST CDS_SEC 1
J 0
(-3100 -1525);
DISPLAY 0.680851 (-3100 -1525);
DISPLAY INVISIBLE (-3100 -1525);
FORCEPROP 0 LASTPIN (-2950 -1900) $PN 1
J 0
(-2940 -1890);
DISPLAY 0.680851 (-2940 -1890);
PAINT MONO (-2940 -1890);
FORCEPROP 0 LASTPIN (-2950 -2100) $PN 2
J 0
(-2940 -2090);
DISPLAY 0.680851 (-2940 -2090);
PAINT MONO (-2940 -2090);
FORCEPROP 0 LASTPIN (-3700 -2000) $PN 3
J 2
(-3710 -1990);
DISPLAY 0.680851 (-3710 -1990);
PAINT MONO (-3710 -1990);
FORCEPROP 0 LAST ROOM E1S_P3V3_BOM2
J 0
(-3450 -1475);
DISPLAY 0.680851 (-3450 -1475);
PAINT RED (-3450 -1475);
FORCEPROP 1 LAST MATERIAL IC
J 2
(-3100 -1790);
DISPLAY 0.723404 (-3100 -1790);
PAINT GREEN (-3100 -1790);
FORCEPROP 2 LAST VALUE APX809-29SAG-7
J 2
(-3100 -1625);
DISPLAY 0.680851 (-3100 -1625);
FORCEPROP 2 LAST PART_TYPE SMLF
J 2
(-3100 -1575);
DISPLAY 0.680851 (-3100 -1575);
FORCEPROP 2 LAST CDS_LIB pure_quanta
J 0
(-3325 -2000);
DISPLAY INVISIBLE (-3325 -2000);
FORCEPROP 1 LAST CDS_LMAN_SYM_OUTLINE -225,200,225,-200
J 2
(-3325 -2000);
DISPLAY 0.468085 (-3325 -2000);
PAINT GREEN (-3325 -2000);
DISPLAY INVISIBLE (-3325 -2000);
FORCEPROP 1 LAST NEEDS_NO_SIZE TRUE
J 2
(-3550 -2160);
DISPLAY 0.723404 (-3550 -2160);
PAINT GREEN (-3550 -2160);
DISPLAY INVISIBLE (-3550 -2160);
FORCEPROP 1 LAST PART_NUMBER AL080929000
J 2
(-3100 -1733);
DISPLAY 0.723404 (-3100 -1733);
PAINT GREEN (-3100 -1733);
DISPLAY INVISIBLE (-3100 -1733);
FORCEPROP 1 LAST PATH I65
J 2
(-3550 -2200);
DISPLAY 0.723404 (-3550 -2200);
PAINT GREEN (-3550 -2200);
DISPLAY INVISIBLE (-3550 -2200);
FORCEADD UNIVERSAL_GND..1
(-2250 -2875);
FORCEPROP 3 LASTPIN (-2250 -2825) SIG_NAME GND\g
J 0
(-2240 -2815);
DISPLAY 0.659574 (-2240 -2815);
PAINT MONO (-2240 -2815);
DISPLAY INVISIBLE (-2240 -2815);
FORCEPROP 2 LAST CDS_LIB pure_quanta_power
J 0
(-2250 -2875);
DISPLAY INVISIBLE (-2250 -2875);
FORCEPROP 1 LAST HDL_POWER GND
J 1
(-2225 -2950);
DISPLAY 0.872340 (-2225 -2950);
PAINT GREEN (-2225 -2950);
DISPLAY INVISIBLE (-2225 -2950);
FORCEPROP 1 LAST PATH I67
J 0
(-2175 -2875);
DISPLAY 0.872340 (-2175 -2875);
PAINT AQUA (-2175 -2875);
DISPLAY INVISIBLE (-2175 -2875);
FORCEADD Q_RES..2
(-2250 -2475);
FORCEPROP 1 LAST LOCATION R8099
J 0
(-2205 -2350);
DISPLAY 0.978723 (-2205 -2350);
FORCEPROP 0 LAST $SEC 1
J 0
(-2200 -2300);
DISPLAY 0.680851 (-2200 -2300);
PAINT MONO (-2200 -2300);
DISPLAY INVISIBLE (-2200 -2300);
FORCEPROP 0 LAST CDS_SEC 1
J 0
(-2200 -2300);
DISPLAY 0.680851 (-2200 -2300);
DISPLAY INVISIBLE (-2200 -2300);
FORCEPROP 1 LASTPIN (-2250 -2375) $PN 1
J 0
(-2245 -2413);
DISPLAY 0.787234 (-2245 -2413);
PAINT MONO (-2245 -2413);
FORCEPROP 1 LASTPIN (-2250 -2575) $PN 2
J 0
(-2245 -2565);
DISPLAY 0.787234 (-2245 -2565);
PAINT MONO (-2245 -2565);
FORCEPROP 1 LAST TOLERANCE 1%
J 0
(-2205 -2450);
DISPLAY 0.978723 (-2205 -2450);
FORCEPROP 1 LAST VALUE 100K
J 0
(-2205 -2400);
DISPLAY 0.978723 (-2205 -2400);
FORCEPROP 1 LAST PACK_TYPE 0402LF
J 0
(-2210 -2650);
DISPLAY 0.978723 (-2210 -2650);
FORCEPROP 1 LAST MATERIAL CHIP
J 0
(-2210 -2550);
DISPLAY 0.978723 (-2210 -2550);
PAINT RED (-2210 -2550);
FORCEPROP 1 LAST WATTAGE 1/16W
J 0
(-2210 -2500);
DISPLAY 0.978723 (-2210 -2500);
FORCEPROP 0 LAST ROOM E1S_P3V3_BOM2
J 0
(-2200 -2700);
DISPLAY 0.680851 (-2200 -2700);
PAINT RED (-2200 -2700);
FORCEPROP 2 LAST CDS_LIB pure_quanta
J 0
(-2250 -2475);
DISPLAY INVISIBLE (-2250 -2475);
FORCEPROP 1 LAST PART_NUMBER CS41002FB09
J 0
(-2210 -2600);
DISPLAY 0.978723 (-2210 -2600);
DISPLAY INVISIBLE (-2210 -2600);
FORCEPROP 1 LAST PATH I68
J 0
(-2200 -2300);
DISPLAY 0.978723 (-2200 -2300);
PAINT WHITE (-2200 -2300);
DISPLAY INVISIBLE (-2200 -2300);
FORCEADD UNIVERSAL_GND..1
(-2775 -2000);
FORCEPROP 3 LASTPIN (-2775 -1950) SIG_NAME GND\g
J 0
(-2765 -1940);
DISPLAY 0.659574 (-2765 -1940);
PAINT MONO (-2765 -1940);
DISPLAY INVISIBLE (-2765 -1940);
FORCEPROP 2 LAST CDS_LIB pure_quanta_power
J 0
(-2775 -2000);
DISPLAY INVISIBLE (-2775 -2000);
FORCEPROP 1 LAST HDL_POWER GND
J 1
(-2750 -2075);
DISPLAY 0.872340 (-2750 -2075);
PAINT GREEN (-2750 -2075);
DISPLAY INVISIBLE (-2750 -2075);
FORCEPROP 1 LAST PATH I69
J 0
(-2700 -2000);
DISPLAY 0.872340 (-2700 -2000);
PAINT AQUA (-2700 -2000);
DISPLAY INVISIBLE (-2700 -2000);
FORCEADD UNIVERSAL_GND..1
(1000 -2025);
FORCEPROP 3 LASTPIN (1000 -1975) SIG_NAME GND\g
J 0
(1010 -1965);
DISPLAY 0.659574 (1010 -1965);
PAINT MONO (1010 -1965);
DISPLAY INVISIBLE (1010 -1965);
FORCEPROP 2 LAST CDS_LIB pure_quanta_power
J 0
(1000 -2025);
DISPLAY INVISIBLE (1000 -2025);
FORCEPROP 1 LAST HDL_POWER GND
J 1
(1025 -2100);
DISPLAY 0.872340 (1025 -2100);
PAINT GREEN (1025 -2100);
DISPLAY INVISIBLE (1025 -2100);
FORCEPROP 1 LAST PATH I7
J 0
(1075 -2025);
DISPLAY 0.872340 (1075 -2025);
PAINT AQUA (1075 -2025);
DISPLAY INVISIBLE (1075 -2025);
FORCEADD Q_RES..2
(-2100 -1600);
FORCEPROP 1 LAST LOCATION R8098
J 0
(-2055 -1475);
DISPLAY 0.978723 (-2055 -1475);
FORCEPROP 0 LAST $SEC 1
J 0
(-2050 -1425);
DISPLAY 0.680851 (-2050 -1425);
PAINT MONO (-2050 -1425);
DISPLAY INVISIBLE (-2050 -1425);
FORCEPROP 0 LAST CDS_SEC 1
J 0
(-2050 -1425);
DISPLAY 0.680851 (-2050 -1425);
DISPLAY INVISIBLE (-2050 -1425);
FORCEPROP 1 LASTPIN (-2100 -1500) $PN 1
J 0
(-2095 -1538);
DISPLAY 0.787234 (-2095 -1538);
PAINT MONO (-2095 -1538);
FORCEPROP 1 LASTPIN (-2100 -1700) $PN 2
J 0
(-2095 -1690);
DISPLAY 0.787234 (-2095 -1690);
PAINT MONO (-2095 -1690);
FORCEPROP 1 LAST PACK_TYPE 0402LF
J 0
(-2060 -1775);
DISPLAY 0.978723 (-2060 -1775);
FORCEPROP 1 LAST MATERIAL EMPTY
J 0
(-2060 -1675);
DISPLAY 0.978723 (-2060 -1675);
PAINT RED (-2060 -1675);
FORCEPROP 1 LAST TOLERANCE 5%
J 0
(-2055 -1575);
DISPLAY 0.978723 (-2055 -1575);
FORCEPROP 1 LAST WATTAGE 1/16W
J 0
(-2060 -1625);
DISPLAY 0.978723 (-2060 -1625);
FORCEPROP 1 LAST VALUE 10K
J 0
(-2055 -1525);
DISPLAY 0.978723 (-2055 -1525);
FORCEPROP 0 LAST ROOM E1S_P3V3_BOM2
J 0
(-2050 -1375);
DISPLAY 0.680851 (-2050 -1375);
PAINT RED (-2050 -1375);
FORCEPROP 2 LAST CDS_LIB pure_quanta
J 0
(-2100 -1600);
DISPLAY INVISIBLE (-2100 -1600);
FORCEPROP 1 LAST PART_NUMBER CS31002JB08
J 0
(-2060 -1725);
DISPLAY 0.978723 (-2060 -1725);
DISPLAY INVISIBLE (-2060 -1725);
FORCEPROP 1 LAST PATH I70
J 0
(-2050 -1425);
DISPLAY 0.978723 (-2050 -1425);
PAINT WHITE (-2050 -1425);
DISPLAY INVISIBLE (-2050 -1425);
FORCEADD Q_RES..1
(-1725 -2100);
FORCEPROP 1 LAST LOCATION R8100
J 0
(-2050 -2100);
DISPLAY 0.978723 (-2050 -2100);
FORCEPROP 0 LAST $SEC 1
J 0
(-2050 -2050);
DISPLAY 0.680851 (-2050 -2050);
PAINT MONO (-2050 -2050);
DISPLAY INVISIBLE (-2050 -2050);
FORCEPROP 0 LAST CDS_SEC 1
J 0
(-2050 -2050);
DISPLAY 0.680851 (-2050 -2050);
DISPLAY INVISIBLE (-2050 -2050);
FORCEPROP 1 LASTPIN (-1825 -2100) $PN 1
J 0
(-1813 -2088);
DISPLAY 0.787234 (-1813 -2088);
PAINT MONO (-1813 -2088);
FORCEPROP 1 LASTPIN (-1625 -2100) $PN 2
J 0
(-1663 -2088);
DISPLAY 0.787234 (-1663 -2088);
PAINT MONO (-1663 -2088);
FORCEPROP 1 LAST PACK_TYPE 0402LF
J 0
(-1475 -2100);
DISPLAY 0.510638 (-1475 -2100);
FORCEPROP 1 LAST TOLERANCE 5%
J 0
(-1550 -2100);
DISPLAY 0.510638 (-1550 -2100);
FORCEPROP 1 LAST MATERIAL CHIP
J 0
(-1800 -2175);
DISPLAY 0.510638 (-1800 -2175);
PAINT RED (-1800 -2175);
FORCEPROP 1 LAST VALUE 0
J 2
(-1575 -2100);
DISPLAY 0.510638 (-1575 -2100);
FORCEPROP 1 LAST WATTAGE 1/16W
J 2
(-1550 -2175);
DISPLAY 0.510638 (-1550 -2175);
FORCEPROP 0 LAST ROOM E1S_P3V3_BOM2
J 0
(-1900 -2000);
DISPLAY 0.680851 (-1900 -2000);
PAINT RED (-1900 -2000);
FORCEPROP 2 LAST CDS_LIB pure_quanta
J 0
(-1725 -2100);
DISPLAY INVISIBLE (-1725 -2100);
FORCEPROP 1 LAST PART_NUMBER CS00002JB13
J 0
(-1800 -2150);
DISPLAY 0.510638 (-1800 -2150);
DISPLAY INVISIBLE (-1800 -2150);
FORCEPROP 1 LAST PATH I71
J 0
(-1775 -1950);
DISPLAY 0.978723 (-1775 -1950);
PAINT WHITE (-1775 -1950);
DISPLAY INVISIBLE (-1775 -1950);
FORCEADD OFFPAGE..2
(-425 -2100);
PAINT AQUA (-425 -2100);
FORCEPROP 2 LAST $XR0 146 
J 0
(-236 -2100);
DISPLAY 0.638298 (-236 -2100);
PAINT MONO (-236 -2100);
FORCEPROP 2 LAST $XR1 81 
J 0
(-116 -2100);
DISPLAY 0.638298 (-116 -2100);
PAINT MONO (-116 -2100);
FORCEPROP 2 LAST CDS_LIB standard
J 0
(-425 -2100);
DISPLAY INVISIBLE (-425 -2100);
FORCEPROP 1 LAST OFFPAGE TRUE
J 0
(-100 -2225);
DISPLAY 0.872340 (-100 -2225);
PAINT AQUA (-100 -2225);
DISPLAY INVISIBLE (-100 -2225);
FORCEPROP 1 LAST COMMENT_BODY TRUE
J 0
(-470 -2195);
DISPLAY 0.872340 (-470 -2195);
PAINT GREEN (-470 -2195);
DISPLAY INVISIBLE (-470 -2195);
FORCEPROP 2 LAST PATH I73
J 0
(-250 -2025);
DISPLAY 0.680851 (-250 -2025);
DISPLAY INVISIBLE (-250 -2025);
FORCEADD UNIVERSAL_POWER..1
R 2
(-4000 -1650);
FORCEPROP 3 LASTPIN (-4000 -1700) SIG_NAME P3V3_E1S_0_R\g
J 0
(-3990 -1690);
DISPLAY 0.659574 (-3990 -1690);
PAINT MONO (-3990 -1690);
DISPLAY INVISIBLE (-3990 -1690);
FORCEPROP 1 LAST HDL_POWER P3V3_E1S_0_R
J 1
(-4000 -1600);
DISPLAY 0.723404 (-4000 -1600);
PAINT GREEN (-4000 -1600);
FORCEPROP 2 LAST CDS_LIB pure_quanta_power
J 0
(-4000 -1650);
DISPLAY INVISIBLE (-4000 -1650);
FORCEPROP 1 LAST PATH I74
J 2
(-4050 -1625);
DISPLAY 0.872340 (-4050 -1625);
PAINT AQUA (-4050 -1625);
DISPLAY INVISIBLE (-4050 -1625);
FORCEADD UNIVERSAL_POWER..1
R 2
(-2100 -1225);
FORCEPROP 3 LASTPIN (-2100 -1275) SIG_NAME P3V3_E1S_0_R\g
J 0
(-2090 -1265);
DISPLAY 0.659574 (-2090 -1265);
PAINT MONO (-2090 -1265);
DISPLAY INVISIBLE (-2090 -1265);
FORCEPROP 1 LAST HDL_POWER P3V3_E1S_0_R
J 1
(-2100 -1175);
DISPLAY 0.723404 (-2100 -1175);
PAINT GREEN (-2100 -1175);
FORCEPROP 2 LAST CDS_LIB pure_quanta_power
J 0
(-2100 -1225);
DISPLAY INVISIBLE (-2100 -1225);
FORCEPROP 1 LAST PATH I75
J 2
(-2150 -1200);
DISPLAY 0.872340 (-2150 -1200);
PAINT AQUA (-2150 -1200);
DISPLAY INVISIBLE (-2150 -1200);
FORCEADD RS31312R..1
(50 1300);
FORCEPROP 1 LAST LOCATION PU292
J 0
(-200 1925);
DISPLAY 0.723404 (-200 1925);
PAINT GREEN (-200 1925);
FORCEPROP 2 LAST SEC 1
J 0
(-175 2150);
DISPLAY 0.680851 (-175 2150);
PAINT MONO (-175 2150);
DISPLAY INVISIBLE (-175 2150);
FORCEPROP 2 LASTPIN (450 1175) $PN 12
J 0
(460 1185);
DISPLAY 0.680851 (460 1185);
PAINT MONO (460 1185);
FORCEPROP 2 LASTPIN (-350 1425) $PN 1
J 2
(-360 1435);
DISPLAY 0.680851 (-360 1435);
PAINT MONO (-360 1435);
FORCEPROP 2 LASTPIN (-350 1225) $PN 3
J 2
(-360 1235);
DISPLAY 0.680851 (-360 1235);
PAINT MONO (-360 1235);
FORCEPROP 2 LASTPIN (450 925) $PN 9
J 0
(460 935);
DISPLAY 0.680851 (460 935);
PAINT MONO (460 935);
FORCEPROP 2 LASTPIN (-350 825) $PN 7
J 2
(-360 835);
DISPLAY 0.680851 (-360 835);
PAINT MONO (-360 835);
FORCEPROP 2 LASTPIN (450 825) $PN 8
J 0
(460 835);
DISPLAY 0.680851 (460 835);
PAINT MONO (460 835);
FORCEPROP 2 LASTPIN (-350 1025) $PN 5
J 2
(-360 1035);
DISPLAY 0.680851 (-360 1035);
PAINT MONO (-360 1035);
FORCEPROP 2 LASTPIN (-350 1325) $PN 2
J 2
(-360 1335);
DISPLAY 0.680851 (-360 1335);
PAINT MONO (-360 1335);
FORCEPROP 2 LASTPIN (450 1075) $PN 11
J 0
(460 1085);
DISPLAY 0.680851 (460 1085);
PAINT MONO (460 1085);
FORCEPROP 2 LASTPIN (450 1775) $PN 10
J 0
(460 1785);
DISPLAY 0.680851 (460 1785);
PAINT MONO (460 1785);
FORCEPROP 2 LASTPIN (-350 925) $PN 6
J 2
(-360 935);
DISPLAY 0.680851 (-360 935);
PAINT MONO (-360 935);
FORCEPROP 2 LASTPIN (-350 1125) $PN 4
J 2
(-360 1135);
DISPLAY 0.680851 (-360 1135);
PAINT MONO (-360 1135);
FORCEPROP 2 LASTPIN (-350 1775) $PN 21_22
J 2
(-360 1785);
DISPLAY 0.680851 (-360 1785);
PAINT MONO (-360 1785);
FORCEPROP 2 LASTPIN (-350 1725) $PN 23
J 2
(-360 1735);
DISPLAY 0.680851 (-360 1735);
PAINT MONO (-360 1735);
FORCEPROP 2 LASTPIN (-350 1675) $PN 24
J 2
(-360 1685);
DISPLAY 0.680851 (-360 1685);
PAINT MONO (-360 1685);
FORCEPROP 2 LASTPIN (-350 1625) $PN 25
J 2
(-360 1635);
DISPLAY 0.680851 (-360 1635);
PAINT MONO (-360 1635);
FORCEPROP 2 LASTPIN (-350 1575) $PN 26
J 2
(-360 1585);
DISPLAY 0.680851 (-360 1585);
PAINT MONO (-360 1585);
FORCEPROP 2 LASTPIN (450 1275) $PN 13
J 0
(460 1285);
DISPLAY 0.680851 (460 1285);
PAINT MONO (460 1285);
FORCEPROP 2 LASTPIN (450 1325) $PN 14
J 0
(460 1335);
DISPLAY 0.680851 (460 1335);
PAINT MONO (460 1335);
FORCEPROP 2 LASTPIN (450 1375) $PN 15
J 0
(460 1385);
DISPLAY 0.680851 (460 1385);
PAINT MONO (460 1385);
FORCEPROP 2 LASTPIN (450 1425) $PN 16
J 0
(460 1435);
DISPLAY 0.680851 (460 1435);
PAINT MONO (460 1435);
FORCEPROP 2 LASTPIN (450 1475) $PN 17
J 0
(460 1485);
DISPLAY 0.680851 (460 1485);
PAINT MONO (460 1485);
FORCEPROP 2 LASTPIN (450 1525) $PN 18
J 0
(460 1535);
DISPLAY 0.680851 (460 1535);
PAINT MONO (460 1535);
FORCEPROP 2 LASTPIN (450 1575) $PN 19
J 0
(460 1585);
DISPLAY 0.680851 (460 1585);
PAINT MONO (460 1585);
FORCEPROP 2 LASTPIN (450 1625) $PN 20
J 0
(460 1635);
DISPLAY 0.680851 (460 1635);
PAINT MONO (460 1635);
FORCEPROP 2 LAST VALUE RS31312R
J 0
(-178 1964);
DISPLAY 0.680851 (-178 1964);
FORCEPROP 2 LAST PART_TYPE SMLF
J 0
(-178 2014);
DISPLAY 0.680851 (-178 2014);
FORCEPROP 1 LAST MATERIAL IC
J 0
(-197 1837);
DISPLAY 0.723404 (-197 1837);
PAINT GREEN (-197 1837);
FORCEPROP 0 LAST ROOM E1S_P12V_MPS_MAM_BOM2
J 0
(-175 2100);
DISPLAY 0.680851 (-175 2100);
PAINT RED (-175 2100);
FORCEPROP 2 LAST CDS_LIB pure_quanta
J 0
(50 1300);
DISPLAY INVISIBLE (50 1300);
FORCEPROP 1 LAST NEEDS_NO_SIZE TRUE
J 0
(50 1300);
DISPLAY 0.723404 (50 1300);
PAINT GREEN (50 1300);
DISPLAY INVISIBLE (50 1300);
FORCEPROP 1 LAST CDS_LMAN_SYM_OUTLINE -250,525,250,-525
J 0
(50 1300);
DISPLAY 0.468085 (50 1300);
PAINT GREEN (50 1300);
DISPLAY INVISIBLE (50 1300);
FORCEPROP 2 LAST SEC_TYPE 
J 0
(-175 2150);
DISPLAY 0.680851 (-175 2150);
DISPLAY INVISIBLE (-175 2150);
FORCEPROP 1 LAST PART_NUMBER AL031312000
J 0
(-200 1875);
DISPLAY 0.723404 (-200 1875);
PAINT GREEN (-200 1875);
DISPLAY INVISIBLE (-200 1875);
FORCEPROP 1 LAST PATH I76
J 0
(50 1300);
DISPLAY 0.723404 (50 1300);
PAINT GREEN (50 1300);
DISPLAY INVISIBLE (50 1300);
FORCEADD UNIVERSAL_GND..1
(975 -1300);
FORCEPROP 3 LASTPIN (975 -1250) SIG_NAME GND\g
J 0
(985 -1240);
DISPLAY 0.659574 (985 -1240);
PAINT MONO (985 -1240);
DISPLAY INVISIBLE (985 -1240);
FORCEPROP 2 LAST CDS_LIB pure_quanta_power
J 0
(975 -1300);
DISPLAY INVISIBLE (975 -1300);
FORCEPROP 1 LAST HDL_POWER GND
J 1
(1000 -1375);
DISPLAY 0.872340 (1000 -1375);
PAINT GREEN (1000 -1375);
DISPLAY INVISIBLE (1000 -1375);
FORCEPROP 1 LAST PATH I8
J 0
(1050 -1300);
DISPLAY 0.872340 (1050 -1300);
PAINT AQUA (1050 -1300);
DISPLAY INVISIBLE (1050 -1300);
FORCEADD Q_CAP..1
(975 -1075);
FORCEPROP 1 LAST LOCATION PC2200
J 0
(1050 -1025);
DISPLAY 0.638298 (1050 -1025);
FORCEPROP 0 LAST $SEC 1
J 0
(1025 -925);
DISPLAY INVISIBLE (1025 -925);
FORCEPROP 0 LAST CDS_SEC 1
J 0
(1025 -925);
DISPLAY INVISIBLE (1025 -925);
FORCEPROP 1 LASTPIN (975 -975) $PN 1
J 0
(985 -995);
DISPLAY 0.787234 (985 -995);
PAINT MONO (985 -995);
DISPLAY INVISIBLE (985 -995);
FORCEPROP 1 LASTPIN (975 -1175) $PN 2
J 0
(985 -1195);
DISPLAY 0.787234 (985 -1195);
PAINT MONO (985 -1195);
DISPLAY INVISIBLE (985 -1195);
FORCEPROP 1 LAST PACK_TYPE C0402
J 0
(1050 -1150);
DISPLAY 0.510638 (1050 -1150);
FORCEPROP 1 LAST MATERIAL X6S
J 0
(1050 -1100);
DISPLAY 0.510638 (1050 -1100);
PAINT RED (1050 -1100);
FORCEPROP 1 LAST VALUE 1UF
J 0
(1050 -1050);
DISPLAY 0.510638 (1050 -1050);
FORCEPROP 1 LAST VOLTAGE 25V
J 0
(1050 -1075);
DISPLAY 0.510638 (1050 -1075);
FORCEPROP 0 LAST ROOM E1S_P3V3_BOM2
J 0
(1050 -925);
DISPLAY 0.680851 (1050 -925);
PAINT RED (1050 -925);
FORCEPROP 2 LAST CDS_LIB pure_quanta
J 0
(975 -1075);
DISPLAY INVISIBLE (975 -1075);
FORCEPROP 1 LAST TOLERANCE 10%
J 0
(1025 -1125);
DISPLAY 0.638298 (1025 -1125);
DISPLAY INVISIBLE (1025 -1125);
FORCEPROP 1 LAST PART_NUMBER CH5104KEB02
J 0
(1050 -1125);
DISPLAY 0.510638 (1050 -1125);
DISPLAY INVISIBLE (1050 -1125);
FORCEPROP 1 LAST PATH I9
J 0
(1025 -925);
DISPLAY 0.978723 (1025 -925);
PAINT WHITE (1025 -925);
DISPLAY INVISIBLE (1025 -925);
FORCEADD CAD_NOTE..1
(2975 100);
FORCEPROP 0 LAST S1 R3955/R3956 CO-LAYOUT
J 0
(2850 -25);
DISPLAY 0.808511 (2850 -25);
PAINT WHITE (2850 -25);
FORCEPROP 2 LAST CDS_LIB pure_quanta_power
J 0
(2975 100);
DISPLAY INVISIBLE (2975 100);
FORCEPROP 1 LAST COMMENT_BODY TRUE
J 0
(3000 200);
DISPLAY 0.978723 (3000 200);
DISPLAY INVISIBLE (3000 200);
FORCEADD DNS..2
(2475 250);
PAINT RED (2475 250);
FORCEPROP 2 LAST CDS_LIB mstr_misc
J 0
(2475 250);
DISPLAY INVISIBLE (2475 250);
FORCEPROP 1 LAST COMMENT_BODY TRUE
R 1
J 0
(2550 25);
DISPLAY 0.872340 (2550 25);
PAINT GREEN (2550 25);
DISPLAY INVISIBLE (2550 25);
FORCEADD QUANTA_TITLE_BLOCK_C..1
(4625 -3350);
FORCEPROP 0 LAST CDS_CON_LAST_MODIFIED Thu Sep 14 16:12:27 2023
J 0
(2740 -3335);
PAINT MONO (2740 -3335);
DISPLAY INVISIBLE (2740 -3335);
FORCEPROP 2 LAST CUSTOM_TXT_CDS <XR_PAGE_TITLE>
J 0
(-3265 1900);
DISPLAY 0.638298 (-3265 1900);
PAINT PINK (-3265 1900);
DISPLAY INVISIBLE (-3265 1900);
FORCEPROP 2 LAST CUSTOM_TXT_CDS <CON_LAST_MODIFIED>
J 0
(2740 -3335);
DISPLAY 0.978723 (2740 -3335);
FORCEPROP 2 LAST CUSTOM_TXT_CDS <NAME_2>
J 0
(1450 -3300);
FORCEPROP 2 LAST CUSTOM_TXT_CDS <Q_NUMBER>
J 0
(3222 -3247);
DISPLAY 1.212766 (3222 -3247);
FORCEPROP 2 LAST CUSTOM_TXT_CDS <Q_REV>
J 0
(4441 -3247);
DISPLAY 1.212766 (4441 -3247);
FORCEPROP 2 LAST CUSTOM_TXT_CDS <CON_PAGE_NUM> OF <CON_TOTAL_PAGES>
J 0
(4179 -3332);
DISPLAY 0.978723 (4179 -3332);
FORCEPROP 2 LAST CUSTOM_TXT_CDS <Q_PROJ>
J 0
(2243 -3248);
DISPLAY 1.212766 (2243 -3248);
FORCEPROP 2 LAST CUSTOM_TXT_CDS <NAME_1>
J 0
(1450 -3175);
FORCEPROP 1 LAST Q_TITLE E1S_HSC_CO_LAYOUT
J 0
(-4741 -3324);
DISPLAY 2.446809 (-4741 -3324);
PAINT GREEN (-4741 -3324);
FORCEPROP 2 LAST CDS_XR_PAGE_TITLE CR-147 : @T6G_MB_LIB.T6G(SCH_1):PAGE147
J 0
(-3265 1900);
DISPLAY 0.638298 (-3265 1900);
PAINT PINK (-3265 1900);
DISPLAY INVISIBLE (-3265 1900);
FORCEPROP 2 LAST CDS_LIB pure_quanta
J 0
(4625 -3350);
PAINT MONO (4625 -3350);
DISPLAY INVISIBLE (4625 -3350);
FORCEPROP 1 LAST CDS_LMAN_SYM_OUTLINE -9475,6775,100,-125
J 0
(4625 -3350);
DISPLAY 0.468085 (4625 -3350);
PAINT GREEN (4625 -3350);
DISPLAY INVISIBLE (4625 -3350);
FORCEPROP 2 LAST PAGE_BORDER TRUE
J 0
(-3265 1900);
DISPLAY 0.638298 (-3265 1900);
PAINT PINK (-3265 1900);
DISPLAY INVISIBLE (-3265 1900);
FORCEPROP 1 LAST COMMENT_BODY TRUE
J 0
(4637 -3363);
DISPLAY 0.978723 (4637 -3363);
PAINT GREEN (4637 -3363);
DISPLAY INVISIBLE (4637 -3363);
FORCEPROP 1 LAST Q_DEPT CCBU
J 1
(862 -3301);
DISPLAY 1.957447 (862 -3301);
PAINT GREEN (862 -3301);
DISPLAY INVISIBLE (862 -3301);
FORCEADD DNS..2
(-1925 -1600);
PAINT RED (-1925 -1600);
FORCEPROP 2 LAST CDS_LIB mstr_misc
J 0
(-1925 -1600);
DISPLAY INVISIBLE (-1925 -1600);
FORCEPROP 1 LAST COMMENT_BODY TRUE
R 1
J 0
(-1850 -1825);
DISPLAY 0.872340 (-1850 -1825);
PAINT GREEN (-1850 -1825);
DISPLAY INVISIBLE (-1850 -1825);
FORCEADD DNS..2
(1675 1400);
PAINT RED (1675 1400);
FORCEPROP 2 LAST CDS_LIB mstr_misc
J 0
(1675 1400);
DISPLAY INVISIBLE (1675 1400);
FORCEPROP 1 LAST COMMENT_BODY TRUE
R 1
J 0
(1750 1175);
DISPLAY 0.872340 (1750 1175);
PAINT GREEN (1750 1175);
DISPLAY INVISIBLE (1750 1175);
FORCEADD DNS..2
(1075 1400);
PAINT RED (1075 1400);
FORCEPROP 2 LAST CDS_LIB mstr_misc
J 0
(1075 1400);
DISPLAY INVISIBLE (1075 1400);
FORCEPROP 1 LAST COMMENT_BODY TRUE
R 1
J 0
(1150 1175);
DISPLAY 0.872340 (1150 1175);
PAINT GREEN (1150 1175);
DISPLAY INVISIBLE (1150 1175);
WIRE 16 -1 (-2050 675)(-2050 875);
WIRE 16 -1 (-1625 600)(-1625 750);
WIRE 16 -1 (-1275 475)(-1275 400);
WIRE 16 -1 (-750 575)(-750 650);
WIRE 16 -1 (-825 1650)(-825 1725);
WIRE 16 -1 (1550 -1825)(1550 -1975);
WIRE 16 -1 (3650 -1875)(3650 -1675);
WIRE 16 -1 (2600 -1250)(3650 -1250);
WIRE 16 -1 (3650 -1250)(3650 -975);
WIRE 16 -1 (3650 -1250)(3650 -1475);
WIRE 16 -1 (1200 925)(1675 925);
WIRE 16 -1 (525 2150)(525 2100);
WIRE 16 -1 (2925 1525)(2925 1650);
WIRE 16 -1 (-4000 -2350)(-4000 -2550);
WIRE 16 -1 (-2250 -2575)(-2250 -2825);
WIRE 16 -1 (-2950 -1900)(-2775 -1900);
WIRE 16 -1 (-2775 -1900)(-2775 -1950);
WIRE 16 -1 (1000 -1800)(1000 -1975);
WIRE 16 -1 (-2100 -1500)(-2100 -1275);
WIRE 16 -1 (975 -1175)(975 -1250);
WIRE 16 -1 (450 1275)(757 1275);
WIRE 16 -1 (757 1325)(757 1275);
WIRE 16 -1 (757 1325)(757 1375);
WIRE 16 -1 (450 1325)(757 1325);
WIRE 16 -1 (757 1375)(757 1425);
WIRE 16 -1 (450 1375)(757 1375);
WIRE 16 -1 (757 1425)(757 1475);
WIRE 16 -1 (757 1425)(450 1425);
WIRE 16 -1 (757 1475)(757 1525);
WIRE 16 -1 (450 1475)(757 1475);
WIRE 16 -1 (757 1525)(757 1575);
WIRE 16 -1 (450 1525)(757 1525);
WIRE 16 -1 (757 1575)(757 1625);
WIRE 16 -1 (450 1575)(757 1575);
WIRE 16 -1 (757 1625)(1050 1625);
WIRE 16 -1 (450 1625)(757 1625);
WIRE 16 -1 (1050 1625)(1650 1625);
WIRE 16 -1 (1050 1500)(1050 1625);
WIRE 16 -1 (1650 1625)(1650 1925);
WIRE 16 -1 (1650 1625)(1650 1500);
WIRE 16 -1 (1650 1925)(2925 1925);
WIRE 16 -1 (2925 1925)(2925 1975);
WIRE 16 -1 (2925 1850)(2925 1925);
WIRE 16 -1 (-350 1575)(-430 1575);
WIRE 16 -1 (-430 1575)(-430 1625);
WIRE 16 -1 (-350 1625)(-430 1625);
WIRE 16 -1 (-430 1625)(-430 1675);
WIRE 16 -1 (-350 1675)(-430 1675);
WIRE 16 -1 (-430 1675)(-430 1725);
WIRE 16 -1 (-350 1725)(-430 1725);
WIRE 16 -1 (-430 1725)(-430 1775);
WIRE 16 -1 (-430 2025)(-430 1775);
WIRE 16 -1 (-430 1775)(-350 1775);
WIRE 16 -1 (-430 2025)(-825 2025);
WIRE 16 -1 (-825 2125)(-825 2025);
WIRE 16 -1 (-825 2025)(-825 1925);
WIRE 16 -1 (1050 1300)(1050 1175);
WIRE 16 -1 (1050 1175)(1200 1175);
WIRE 16 -1 (450 1175)(1050 1175);
FORCEPROP 2 LAST SIG_NAME P12V_E1S_AVIN_PD_0
J 0
(540 1185);
DISPLAY 0.574468 (540 1185);
WIRE 16 -1 (2050 1225)(2050 1075);
WIRE 16 -1 (2050 1075)(2050 1000);
WIRE 16 -1 (2050 1075)(1650 1075);
WIRE 16 -1 (1650 1300)(1650 1075);
WIRE 16 -1 (450 1075)(1650 1075);
FORCEPROP 2 LAST SIG_NAME P12V_E1S_OV_FB_0
J 0
(540 1085);
DISPLAY 0.574468 (540 1085);
FORCEPROP 2 LASTPROP $XRERR UNIQUE?
J 0
(300 1085);
DISPLAY 0.638298 (300 1085);
PAINT MONO (300 1085);
DISPLAY INVISIBLE (300 1085);
WIRE 16 -1 (525 1900)(525 1775);
WIRE 16 -1 (1275 1775)(525 1775);
FORCEPROP 2 LAST SIG_NAME HP_LVC3_E1S_0_HSC_PWRGD
J 0
(565 1785);
DISPLAY 0.574468 (565 1785);
WIRE 16 -1 (450 1775)(525 1775);
WIRE 16 -1 (1000 925)(450 925);
FORCEPROP 2 LAST SIG_NAME P12V_E1S_FLTB_0
J 0
(540 935);
DISPLAY 0.574468 (540 935);
FORCEPROP 2 LASTPROP $XRERR UNIQUE?
J 0
(300 935);
DISPLAY 0.638298 (300 935);
PAINT MONO (300 935);
DISPLAY INVISIBLE (300 935);
WIRE 16 -1 (2025 225)(2375 225);
WIRE 16 -1 (2025 400)(2025 225);
WIRE 16 -1 (2375 400)(2025 400);
WIRE 16 -1 (1750 400)(2025 400);
WIRE 16 -1 (1750 825)(1750 400);
WIRE 16 -1 (1125 825)(1750 825);
WIRE 16 -1 (1125 650)(1125 825);
WIRE 16 -1 (675 825)(1125 825);
WIRE 16 -1 (675 650)(675 825);
FORCEPROP 2 LAST SIG_NAME P12V_E1S_IMON_0
J 0
(540 835);
DISPLAY 0.574468 (540 835);
FORCEPROP 2 LASTPROP $XRERR UNIQUE?
J 0
(300 835);
DISPLAY 0.638298 (300 835);
PAINT MONO (300 835);
DISPLAY INVISIBLE (300 835);
WIRE 16 -1 (450 825)(675 825);
WIRE 16 -1 (-1175 1425)(-350 1425);
FORCEPROP 2 LAST SIG_NAME P12V_E1S_EN_0_R2
J 0
(-860 1435);
DISPLAY 0.574468 (-860 1435);
FORCEPROP 2 LASTPROP $XRERR UNIQUE?
J 0
(-1100 1435);
DISPLAY 0.638298 (-1100 1435);
PAINT MONO (-1100 1435);
DISPLAY INVISIBLE (-1100 1435);
WIRE 16 -1 (-350 1325)(-675 1325);
WIRE 16 -1 (-675 1325)(-675 1225);
WIRE 16 -1 (-675 1225)(-350 1225);
WIRE 16 -1 (-675 1225)(-1150 1225);
WIRE 16 -1 (-350 1125)(-2050 1125);
FORCEPROP 2 LAST SIG_NAME P12V_E1S_TIMER_0
J 0
(-860 1135);
DISPLAY 0.574468 (-860 1135);
FORCEPROP 2 LASTPROP $XRERR UNIQUE?
J 0
(-1100 1135);
DISPLAY 0.638298 (-1100 1135);
PAINT MONO (-1100 1135);
DISPLAY INVISIBLE (-1100 1135);
WIRE 16 -1 (-2050 1125)(-2050 1075);
WIRE 16 -1 (-350 1025)(-1275 1025);
WIRE 16 -1 (-1275 1025)(-1625 1025);
FORCEPROP 2 LAST SIG_NAME P12V_E1S_ISET_0
J 0
(-1310 1035);
DISPLAY 0.574468 (-1310 1035);
FORCEPROP 2 LASTPROP $XRERR UNIQUE?
J 0
(-1550 1035);
DISPLAY 0.638298 (-1550 1035);
PAINT MONO (-1550 1035);
DISPLAY INVISIBLE (-1550 1035);
WIRE 16 -1 (-1275 1025)(-1275 950);
WIRE 16 -1 (-1625 1025)(-1625 950);
WIRE 16 -1 (-350 925)(-750 925);
FORCEPROP 2 LAST SIG_NAME P12V_E1S_SS_0
J 0
(-785 935);
DISPLAY 0.574468 (-785 935);
FORCEPROP 2 LASTPROP $XRERR UNIQUE?
J 0
(-1025 935);
DISPLAY 0.638298 (-1025 935);
PAINT MONO (-1025 935);
DISPLAY INVISIBLE (-1025 935);
WIRE 16 -1 (-750 925)(-750 850);
WIRE 16 -1 (-409 825)(-350 825);
WIRE 16 -1 (-409 741)(-409 825);
WIRE 16 -1 (1575 -875)(1575 -1250);
WIRE 16 -1 (975 -875)(1575 -875);
WIRE 16 -1 (1575 -1250)(1800 -1250);
WIRE 16 -1 (975 -975)(975 -875);
WIRE 16 -1 (975 -875)(975 -800);
WIRE 16 -1 (675 -1750)(675 -1875);
WIRE 16 -1 (675 -1875)(325 -1875);
WIRE 16 -1 (325 -1750)(325 -1875);
WIRE 16 -1 (325 -1875)(325 -1975);
WIRE 16 -1 (2775 -1550)(2775 -1975);
WIRE 16 -1 (2600 -1550)(2775 -1550);
WIRE 16 -1 (2775 -1975)(3050 -1975);
WIRE 16 -1 (3050 -1900)(3050 -1975);
WIRE 16 -1 (3050 -1975)(3050 -2100);
WIRE 16 -1 (675 450)(675 270);
WIRE 16 -1 (675 270)(1125 270);
WIRE 16 -1 (1125 270)(1125 450);
WIRE 16 -1 (1125 270)(1125 200);
WIRE 16 -1 (2050 800)(2050 650);
WIRE 16 -1 (2050 650)(2250 650);
WIRE 16 -1 (2250 650)(2575 650);
WIRE 16 -1 (2250 650)(2250 625);
WIRE 16 -1 (2575 650)(2575 800);
WIRE 16 -1 (2575 1525)(2575 1425);
WIRE 16 -1 (2475 1525)(2575 1525);
WIRE 16 -1 (2475 1575)(2475 1525);
WIRE 16 -1 (2050 1525)(2475 1525);
WIRE 16 -1 (2050 1425)(2050 1525);
WIRE 16 -1 (-4000 -2000)(-3700 -2000);
WIRE 16 -1 (-4000 -1700)(-4000 -2000);
WIRE 16 -1 (-4000 -2000)(-4000 -2150);
WIRE 16 2175 (2075 450)(2775 450);
WIRE 16 2175 (2075 450)(2075 100);
WIRE 16 2175 (2775 450)(2775 100);
WIRE 16 2175 (2075 100)(2775 100);
WIRE 16 -1 (2575 400)(3675 400);
FORCEPROP 2 LAST SIG_NAME P12V_E1S_0_ISENSE_MPS_MAM
J 0
(2915 410);
DISPLAY 0.574468 (2915 410);
WIRE 16 -1 (2575 225)(3650 225);
FORCEPROP 2 LAST SIG_NAME P12V_E1S_0_ISENSE_MPS_TIC
J 0
(2915 235);
DISPLAY 0.574468 (2915 235);
WIRE 16 -1 (325 -1550)(325 -1450);
WIRE 16 -1 (325 -1450)(675 -1450);
WIRE 16 -1 (1800 -1450)(675 -1450);
FORCEPROP 2 LAST SIG_NAME P3V3_E1S_MODE_0
J 0
(1265 -1440);
DISPLAY 0.574468 (1265 -1440);
FORCEPROP 2 LASTPROP $XRERR UNIQUE?
J 0
(1025 -1440);
DISPLAY 0.638298 (1025 -1440);
PAINT MONO (1025 -1440);
DISPLAY INVISIBLE (1025 -1440);
WIRE 16 -1 (675 -1550)(675 -1450);
WIRE 16 -1 (-1275 750)(-1275 675);
FORCEPROP 2 LAST SIG_NAME P12V_E1S_ISET_0_R
J 0
(-1260 685);
DISPLAY 0.574468 (-1260 685);
FORCEPROP 2 LASTPROP $XRERR UNIQUE?
J 0
(-1500 685);
DISPLAY 0.638298 (-1500 685);
PAINT MONO (-1500 685);
DISPLAY INVISIBLE (-1500 685);
WIRE 16 -1 (-1375 1425)(-2050 1425);
FORCEPROP 2 LAST SIG_NAME E1S_0_P12V_EN
J 0
(-2010 1435);
DISPLAY 0.638298 (-2010 1435);
WIRE 16 -1 (3175 1050)(2575 1050);
FORCEPROP 2 LAST SIG_NAME P12V_E1S_AVIN_PD_0
J 0
(2690 1060);
DISPLAY 0.574468 (2690 1060);
WIRE 16 -1 (2575 1225)(2575 1050);
WIRE 16 -1 (2575 1050)(2575 1000);
WIRE 16 3135 (1200 2600)(2400 2600);
WIRE 16 3135 (1200 2700)(2400 2700);
WIRE 16 3135 (1975 2825)(1975 2225);
WIRE 16 3135 (1200 2500)(2400 2500);
WIRE 16 3135 (1200 2400)(2400 2400);
WIRE 16 3135 (1175 2850)(2425 2850);
WIRE 16 3135 (1175 2200)(1175 2850);
WIRE 16 3135 (2425 2200)(2425 2850);
WIRE 16 3135 (1175 2200)(2425 2200);
WIRE 16 3135 (1200 2300)(2400 2300);
WIRE 16 -1 (1800 -1350)(850 -1350);
FORCEPROP 2 LAST SIG_NAME P3V3_E1S_EN_0_R2
J 0
(1240 -1340);
DISPLAY 0.574468 (1240 -1340);
FORCEPROP 2 LASTPROP $XRERR UNIQUE?
J 0
(1000 -1340);
DISPLAY 0.638298 (1000 -1340);
PAINT MONO (1000 -1340);
DISPLAY INVISIBLE (1000 -1340);
WIRE 16 -1 (1000 -1600)(1000 -1500);
WIRE 16 -1 (1000 -1500)(1800 -1500);
FORCEPROP 2 LAST SIG_NAME P3V3_E1S_ILIMIT_0
J 0
(1215 -1490);
DISPLAY 0.574468 (1215 -1490);
FORCEPROP 2 LASTPROP $XRERR UNIQUE?
J 0
(975 -1490);
DISPLAY 0.638298 (975 -1490);
PAINT MONO (975 -1490);
DISPLAY INVISIBLE (975 -1490);
WIRE 16 3135 (1550 2825)(1550 2225);
WIRE 16 -1 (-2100 -1700)(-2100 -2100);
WIRE 16 -1 (-2100 -2100)(-1825 -2100);
WIRE 16 -1 (-2100 -2100)(-2250 -2100);
WIRE 16 -1 (-2250 -2375)(-2250 -2100);
WIRE 16 -1 (-2950 -2100)(-2250 -2100);
FORCEPROP 2 LAST SIG_NAME P3V3_E1S_PWRGD_0_R1
J 0
(-2835 -2090);
DISPLAY 0.680851 (-2835 -2090);
FORCEPROP 2 LASTPROP $XRERR UNIQUE?
J 0
(-3075 -2090);
DISPLAY 0.638298 (-3075 -2090);
PAINT MONO (-3075 -2090);
DISPLAY INVISIBLE (-3075 -2090);
WIRE 16 -1 (-1625 -2100)(-475 -2100);
FORCEPROP 2 LAST SIG_NAME P3V3_E1S_PWRGD_0_R
J 0
(-1185 -2090);
DISPLAY 0.680851 (-1185 -2090);
WIRE 16 -1 (650 -1350)(-125 -1350);
FORCEPROP 2 LAST SIG_NAME E1S_0_P3V3_EN
J 0
(-110 -1340);
DISPLAY 0.638298 (-110 -1340);
WIRE 16 -1 (1550 -1550)(1800 -1550);
WIRE 16 -1 (1550 -1625)(1550 -1550);
FORCEPROP 2 LAST SIG_NAME P3V3_E1S_DVDT_0
J 0
(1265 -1540);
DISPLAY 0.574468 (1265 -1540);
FORCEPROP 2 LASTPROP $XRERR UNIQUE?
J 0
(1025 -1540);
DISPLAY 0.638298 (1025 -1540);
PAINT MONO (1025 -1540);
DISPLAY INVISIBLE (1025 -1540);
WIRE 16 -1 (3050 -1700)(3050 -1450);
WIRE 16 -1 (2600 -1450)(3050 -1450);
FORCEPROP 2 LAST SIG_NAME P3V3_E1S_GATE_0_PU293
J 0
(2690 -1440);
DISPLAY 0.574468 (2690 -1440);
FORCEPROP 2 LASTPROP $XRERR UNIQUE?
J 0
(2450 -1440);
DISPLAY 0.638298 (2450 -1440);
PAINT MONO (2450 -1440);
DISPLAY INVISIBLE (2450 -1440);
WIRE 16 2175 (-4650 2325)(-2947 2325);
WIRE 16 2175 (-4650 3225)(-4650 2325);
WIRE 16 2175 (-2947 3225)(-2947 2325);
WIRE 16 2175 (-4650 3225)(-2947 3225);
DOT 1 (1650 1075);
DOT 1 (1050 1175);
DOT 1 (-675 1225);
DOT 1 (757 1325);
DOT 1 (-430 1625);
DOT 1 (525 1775);
DOT 1 (-430 1775);
DOT 1 (-1275 1025);
DOT 1 (2475 1525);
DOT 1 (2575 1050);
DOT 1 (1650 1625);
DOT 1 (2925 1925);
DOT 1 (757 1425);
DOT 1 (1050 1625);
DOT 1 (757 1525);
DOT 1 (757 1475);
DOT 1 (757 1375);
DOT 1 (-2250 -2100);
DOT 1 (-2100 -2100);
DOT 1 (325 -1875);
DOT 1 (675 -1450);
DOT 1 (3050 -1975);
DOT 1 (3650 -1250);
DOT 1 (2050 1075);
DOT 1 (2025 400);
DOT 1 (675 825);
DOT 1 (-430 1675);
DOT 1 (-825 2025);
DOT 1 (-430 1725);
DOT 1 (1125 825);
DOT 1 (1125 270);
DOT 1 (2250 650);
DOT 1 (-4000 -2000);
DOT 1 (975 -875);
DOT 1 (757 1625);
DOT 1 (757 1575);
FORCENOTE
2ND SOURCE OF PU294
(-725 2425) 0;
DISPLAY LEFT (-725 2425);
DISPLAY 1.595745 (-725 2425);
FORCENOTE
VTH>1.391V(HIGH)
(-2525 1209) 0;
DISPLAY LEFT (-2525 1209);
DISPLAY 1.021277 (-2525 1209);
PAINT WHITE (-2525 1209);
FORCENOTE
START UP TIME:8.62MS
(-800 400) 0;
DISPLAY LEFT (-800 400);
DISPLAY 1.021277 (-800 400);
PAINT WHITE (-800 400);
FORCENOTE
PR3950
(1250 2625) 0;
DISPLAY LEFT (1250 2625);
DISPLAY 1.021277 (1250 2625);
FORCENOTE
DE-POP
(1600 2625) 0;
DISPLAY LEFT (1600 2625);
DISPLAY 1.021277 (1600 2625);
FORCENOTE
MP5022C
(1575 2725) 0;
DISPLAY LEFT (1575 2725);
DISPLAY 1.021277 (1575 2725);
FORCENOTE
MP5025A/
(2025 2775) 0;
DISPLAY LEFT (2025 2775);
DISPLAY 1.021277 (2025 2775);
FORCENOTE
MP5025C/
(1575 2775) 0;
DISPLAY LEFT (1575 2775);
DISPLAY 1.021277 (1575 2775);
FORCENOTE
PR3952
(1250 2525) 0;
DISPLAY LEFT (1250 2525);
DISPLAY 1.021277 (1250 2525);
FORCENOTE
PR3953
(1250 2425) 0;
DISPLAY LEFT (1250 2425);
DISPLAY 1.021277 (1250 2425);
FORCENOTE
PU292 OPTIONAL BOM
(1200 2875) 0;
DISPLAY LEFT (1200 2875);
DISPLAY 1.021277 (1200 2875);
FORCENOTE
MP5022A
(2025 2725) 0;
DISPLAY LEFT (2025 2725);
DISPLAY 1.021277 (2025 2725);
FORCENOTE
DE-POP
(2025 2425) 0;
DISPLAY LEFT (2025 2425);
DISPLAY 1.021277 (2025 2425);
FORCENOTE
2ND SOURCE OF PU295
(1475 -675) 0;
DISPLAY LEFT (1475 -675);
DISPLAY 1.595745 (1475 -675);
FORCENOTE
PC2205
(1250 2225) 0;
DISPLAY LEFT (1250 2225);
DISPLAY 1.021277 (1250 2225);
FORCENOTE
POP
(1600 2225) 0;
DISPLAY LEFT (1600 2225);
DISPLAY 1.021277 (1600 2225);
FORCENOTE
VIMON(MAX)= 1.569V @ IOUT=2.8A
(-475 75) 0;
DISPLAY LEFT (-475 75);
DISPLAY 1.021277 (-475 75);
PAINT WHITE (-475 75);
FORCENOTE
DE-POP
(2025 2225) 0;
DISPLAY LEFT (2025 2225);
DISPLAY 1.021277 (2025 2225);
FORCENOTE
DE-POP
(2025 2325) 0;
DISPLAY LEFT (2025 2325);
DISPLAY 1.021277 (2025 2325);
FORCENOTE
PUSH PULL OUTPUT
(-3775 -2325) 0;
DISPLAY LEFT (-3775 -2325);
DISPLAY 1.276596 (-3775 -2325);
FORCENOTE
CURRENT LIMIT
(700 -2159) 0;
DISPLAY LEFT (700 -2159);
DISPLAY 1.021277 (700 -2159);
PAINT WHITE (700 -2159);
FORCENOTE
=0.75A
(700 -2225) 0;
DISPLAY LEFT (700 -2225);
DISPLAY 1.021277 (700 -2225);
PAINT WHITE (700 -2225);
FORCENOTE
START UP TIME:4.7MS
(1775 -2275) 0;
DISPLAY LEFT (1775 -2275);
DISPLAY 1.021277 (1775 -2275);
PAINT WHITE (1775 -2275);
FORCENOTE
TDELAY: 6.29MS
(-2575 375) 0;
DISPLAY LEFT (-2575 375);
DISPLAY 1.021277 (-2575 375);
PAINT WHITE (-2575 375);
FORCENOTE
TFAULT: 1.27MS
(-2575 450) 0;
DISPLAY LEFT (-2575 450);
DISPLAY 1.021277 (-2575 450);
PAINT WHITE (-2575 450);
FORCENOTE
PR3957
(1250 2325) 0;
DISPLAY LEFT (1250 2325);
DISPLAY 1.021277 (1250 2325);
FORCENOTE
POP
(1600 2425) 0;
DISPLAY LEFT (1600 2425);
DISPLAY 1.021277 (1600 2425);
FORCENOTE
POP
(1600 2325) 0;
DISPLAY LEFT (1600 2325);
DISPLAY 1.021277 (1600 2325);
FORCENOTE
DE-POP
(1600 2525) 0;
DISPLAY LEFT (1600 2525);
DISPLAY 1.021277 (1600 2525);
FORCENOTE
POP
(2075 2625) 0;
DISPLAY LEFT (2075 2625);
DISPLAY 1.021277 (2075 2625);
FORCENOTE
POP
(2075 2525) 0;
DISPLAY LEFT (2075 2525);
DISPLAY 1.021277 (2075 2525);
FORCENOTE
OCP=0.75A
(-4600 2525) 0;
DISPLAY LEFT (-4600 2525);
DISPLAY 1.021277 (-4600 2525);
FORCENOTE
DESIGN SPECIFICATION
(-4613 3144) 0;
DISPLAY LEFT (-4613 3144);
DISPLAY 1.170213 (-4613 3144);
FORCENOTE
OCP=MAX*1.3=2.71A
(-4600 2900) 0;
DISPLAY LEFT (-4600 2900);
DISPLAY 1.021277 (-4600 2900);
FORCENOTE
IMAX=2.083A
(-4600 2975) 0;
DISPLAY LEFT (-4600 2975);
DISPLAY 1.021277 (-4600 2975);
FORCENOTE
P3V3_E1S_0_R
(-4600 2675) 0;
DISPLAY LEFT (-4600 2675);
DISPLAY 1.021277 (-4600 2675);
FORCENOTE
IMAX=0.025A
(-4600 2600) 0;
DISPLAY LEFT (-4600 2600);
DISPLAY 1.021277 (-4600 2600);
FORCENOTE
P12V_E1S_0
(-4600 3050) 0;
DISPLAY LEFT (-4600 3050);
DISPLAY 1.021277 (-4600 3050);
FORCENOTE
ENABLE:
(-2525 1275) 0;
DISPLAY LEFT (-2525 1275);
DISPLAY 1.021277 (-2525 1275);
PAINT WHITE (-2525 1275);
QUIT
